FILE_TYPE = MACRO_DRAWING;
SET COLOR_WIRE YELLOW;
SET COLOR_PROP MONO;
SET COLOR_DOT WHITE;
SET COLOR_ARC YELLOW;
SET COLOR_BODY GREEN;
SET COLOR_NOTE MONO;
SET PROP_DISPLAY VALUE;
SET PAGE_NUMBER P208;
FORCEADD OFFPAGE..2
(-975 4800);
FORCEPROP 2 LAST $XR0 206 
J 0
(-786 4800);
DISPLAY 0.638298 (-786 4800);
PAINT MONO (-786 4800);
FORCEPROP 1 LAST COMMENT_BODY TRUE
J 0
(-1020 4705);
DISPLAY 1.723404 (-1020 4705);
PAINT GREEN (-1020 4705);
DISPLAY INVISIBLE (-1020 4705);
FORCEPROP 1 LAST OFFPAGE TRUE
J 0
(-650 4675);
DISPLAY 1.723404 (-650 4675);
PAINT GREEN (-650 4675);
DISPLAY INVISIBLE (-650 4675);
FORCEPROP 2 LAST CDS_LIB mstr_standard
J 2
(-975 4800);
DISPLAY 1.936170 (-975 4800);
PAINT ORANGE (-975 4800);
DISPLAY INVISIBLE (-975 4800);
FORCEPROP 2 LAST BOM_COST PROC_VRD_VCCIN_CPU0
J 0
(-775 4850);
DISPLAY 1.446809 (-775 4850);
PAINT MONO (-775 4850);
DISPLAY INVISIBLE (-775 4850);
FORCEPROP 2 LAST PATH I1
J 0
(-770 4850);
DISPLAY 1.021277 (-770 4850);
PAINT ORANGE (-770 4850);
DISPLAY INVISIBLE (-770 4850);
FORCEPROP 2 LAST ROOM PVCCIN_CPU1_PWR_VR
J 0
(-1375 4875);
DISPLAY 1.936170 (-1375 4875);
PAINT ORANGE (-1375 4875);
DISPLAY INVISIBLE (-1375 4875);
FORCEADD GND..1
(-400 3050);
FORCEPROP 3 LASTPIN (-400 3100) SIG_NAME GND\g
J 0
(-390 3110);
DISPLAY 0.659574 (-390 3110);
PAINT MONO (-390 3110);
DISPLAY INVISIBLE (-390 3110);
FORCEPROP 1 LAST HDL_POWER GND
J 0
(-400 3200);
DISPLAY 1.723404 (-400 3200);
PAINT GREEN (-400 3200);
DISPLAY INVISIBLE (-400 3200);
FORCEPROP 1 LAST BODY_TYPE PLUMBING
J 0
(-445 3007);
DISPLAY 0.340426 (-445 3007);
PAINT GREEN (-445 3007);
DISPLAY INVISIBLE (-445 3007);
FORCEPROP 1 LAST PATH I10
J 0
(-325 3050);
DISPLAY 0.872340 (-325 3050);
PAINT AQUA (-325 3050);
DISPLAY INVISIBLE (-325 3050);
FORCEPROP 1 LAST VOLTAGE 0
J 0
(-400 3050);
PAINT SKYBLUE (-400 3050);
DISPLAY INVISIBLE (-400 3050);
FORCEPROP 2 LAST CDS_LIB mstr_symbols
J 0
(-400 3050);
DISPLAY 1.936170 (-400 3050);
PAINT ORANGE (-400 3050);
DISPLAY INVISIBLE (-400 3050);
FORCEPROP 1 LAST SIZE 1B
J 0
(-325 3000);
DISPLAY 1.723404 (-325 3000);
PAINT GREEN (-325 3000);
DISPLAY INVISIBLE (-325 3000);
FORCEPROP 2 LAST BOM_COST PROC_VRD_VCCIN_CPU0
J 0
(-775 3125);
DISPLAY 1.446809 (-775 3125);
PAINT MONO (-775 3125);
DISPLAY INVISIBLE (-775 3125);
FORCEPROP 2 LAST ROOM PVCCIN_CPU1_PWR_VR
J 0
(-950 3125);
DISPLAY 1.936170 (-950 3125);
PAINT ORANGE (-950 3125);
DISPLAY INVISIBLE (-950 3125);
FORCEADD INDUCTOR..1
(-1475 3625);
FORCEPROP 1 LAST MATERIAL IND
J 0
(-1435 3515);
DISPLAY 0.617021 (-1435 3515);
PAINT SKYBLUE (-1435 3515);
FORCEPROP 1 LAST PART_NUMBER D92183-034
J 0
(-1600 3575);
DISPLAY 0.617021 (-1600 3575);
PAINT BLUE (-1600 3575);
FORCEPROP 1 LASTPIN (-1375 3625) $PN 2
J 2
(-1365 3635);
DISPLAY 0.617021 (-1365 3635);
PAINT WHITE (-1365 3635);
FORCEPROP 1 LAST LOCATION L1D2
J 0
(-1550 3675);
DISPLAY 0.617021 (-1550 3675);
PAINT AQUA (-1550 3675);
FORCEPROP 1 LASTPIN (-1575 3625) $PN 1
J 0
(-1575 3635);
DISPLAY 0.617021 (-1575 3635);
PAINT WHITE (-1575 3635);
FORCEPROP 1 LAST PACK_TYPE SM
J 0
(-1310 3515);
DISPLAY 0.617021 (-1310 3515);
PAINT SKYBLUE (-1310 3515);
FORCEPROP 1 LAST VALUE 0.12UH
J 2
(-1480 3515);
DISPLAY 0.617021 (-1480 3515);
PAINT SKYBLUE (-1480 3515);
FORCEPROP 2 LAST CDS_SEC 1
J 0
(-1575 3825);
PAINT MONO (-1575 3825);
DISPLAY INVISIBLE (-1575 3825);
FORCEPROP 2 LAST $SEC 1
J 0
(-1575 3825);
PAINT MONO (-1575 3825);
DISPLAY INVISIBLE (-1575 3825);
FORCEPROP 2 LAST CDS_LOCATION L1D2
J 0
(-1575 3675);
DISPLAY 0.617021 (-1575 3675);
PAINT AQUA (-1575 3675);
DISPLAY INVISIBLE (-1575 3675);
FORCEPROP 1 LAST PATH I11
J 0
(-1575 3775);
DISPLAY 0.978723 (-1575 3775);
PAINT ORANGE (-1575 3775);
DISPLAY INVISIBLE (-1575 3775);
FORCEPROP 2 LAST ROOM PVCCIN_CPU1_PWR_VR
J 0
(-1575 3725);
DISPLAY 1.361702 (-1575 3725);
PAINT ORANGE (-1575 3725);
DISPLAY INVISIBLE (-1575 3725);
FORCEPROP 2 LAST CDS_LIB mstr_discrete
J 0
(-1475 3625);
PAINT ORANGE (-1475 3625);
DISPLAY INVISIBLE (-1475 3625);
FORCEADD CAPP..1
(-1450 2625);
FORCEPROP 1 LAST TOLERANCE 20%
J 0
(-1400 2625);
DISPLAY 0.617021 (-1400 2625);
PAINT SKYBLUE (-1400 2625);
FORCEPROP 1 LAST VALUE 470UF
J 0
(-1400 2675);
DISPLAY 0.617021 (-1400 2675);
PAINT SKYBLUE (-1400 2675);
FORCEPROP 1 LAST PACK_TYPE 3018
J 0
(-1400 2475);
DISPLAY 0.617021 (-1400 2475);
PAINT SKYBLUE (-1400 2475);
FORCEPROP 1 LAST PART_NUMBER 699013-049
J 0
(-1400 2425);
DISPLAY 0.617021 (-1400 2425);
PAINT BLUE (-1400 2425);
FORCEPROP 1 LASTPIN (-1450 2525) $PN 2
J 0
(-1440 2510);
DISPLAY 0.617021 (-1440 2510);
PAINT GREEN (-1440 2510);
FORCEPROP 1 LAST MATERIAL ALUM
J 0
(-1400 2525);
DISPLAY 0.617021 (-1400 2525);
PAINT SKYBLUE (-1400 2525);
FORCEPROP 1 LAST LOCATION C9P8
J 0
(-1400 2725);
DISPLAY 0.617021 (-1400 2725);
PAINT AQUA (-1400 2725);
FORCEPROP 1 LASTPIN (-1450 2725) $PN 1
J 0
(-1440 2710);
DISPLAY 0.617021 (-1440 2710);
PAINT GREEN (-1440 2710);
FORCEPROP 2 LAST SEC_TYPE 3018
J 0
(-1385 2835);
DISPLAY 1.021277 (-1385 2835);
PAINT ORANGE (-1385 2835);
DISPLAY INVISIBLE (-1385 2835);
FORCEPROP 2 LAST SEC 1
J 0
(-1400 2825);
PAINT MONO (-1400 2825);
DISPLAY INVISIBLE (-1400 2825);
FORCEPROP 2 LAST BOM_COST PROC_VRD_VCCIN_CPU0
J 0
(-1400 2775);
PAINT MONO (-1400 2775);
DISPLAY INVISIBLE (-1400 2775);
FORCEPROP 1 LAST VOLTAGE 2.5V
J 0
(-1400 2575);
PAINT SKYBLUE (-1400 2575);
DISPLAY INVISIBLE (-1400 2575);
FORCEPROP 2 LAST CDS_LOCATION C9P8
J 0
(-1400 2725);
DISPLAY 0.617021 (-1400 2725);
PAINT AQUA (-1400 2725);
DISPLAY INVISIBLE (-1400 2725);
FORCEPROP 1 LAST PATH I12
J 0
(-1400 2775);
DISPLAY 0.978723 (-1400 2775);
PAINT ORANGE (-1400 2775);
DISPLAY INVISIBLE (-1400 2775);
FORCEPROP 2 LAST ROOM PVCCIN_CPU1_DECAP_VR
J 0
(-1400 2750);
PAINT MONO (-1400 2750);
DISPLAY INVISIBLE (-1400 2750);
FORCEPROP 2 LAST CDS_LIB mstr_discrete
J 0
(-1450 2625);
PAINT MONO (-1450 2625);
DISPLAY INVISIBLE (-1450 2625);
FORCEADD GND..1
(-1000 2275);
FORCEPROP 3 LASTPIN (-1000 2325) SIG_NAME GND\g
J 0
(-990 2335);
DISPLAY 0.659574 (-990 2335);
PAINT MONO (-990 2335);
DISPLAY INVISIBLE (-990 2335);
FORCEPROP 1 LAST HDL_POWER GND
J 0
(-1000 2425);
DISPLAY 0.893617 (-1000 2425);
PAINT GREEN (-1000 2425);
DISPLAY INVISIBLE (-1000 2425);
FORCEPROP 1 LAST BODY_TYPE PLUMBING
J 0
(-1045 2232);
DISPLAY 0.340426 (-1045 2232);
PAINT GREEN (-1045 2232);
DISPLAY INVISIBLE (-1045 2232);
FORCEPROP 1 LAST VOLTAGE 0
J 0
(-1000 2275);
PAINT SKYBLUE (-1000 2275);
DISPLAY INVISIBLE (-1000 2275);
FORCEPROP 2 LAST CDS_LIB mstr_symbols
J 1
(-1000 2275);
PAINT ORANGE (-1000 2275);
DISPLAY INVISIBLE (-1000 2275);
FORCEPROP 1 LAST PATH I13
J 0
(-925 2275);
DISPLAY 0.872340 (-925 2275);
PAINT AQUA (-925 2275);
DISPLAY INVISIBLE (-925 2275);
FORCEPROP 1 LAST SIZE 1B
J 0
(-925 2225);
DISPLAY 0.893617 (-925 2225);
PAINT GREEN (-925 2225);
DISPLAY INVISIBLE (-925 2225);
FORCEPROP 2 LAST BOM_COST PROC_VRD_VCCIN_CPU0
J 0
(-1375 2350);
PAINT MONO (-1375 2350);
DISPLAY INVISIBLE (-1375 2350);
FORCEPROP 2 LAST ROOM PVCCIN_CPU1_DECAP_VR
J 0
(-1550 2350);
PAINT ORANGE (-1550 2350);
DISPLAY INVISIBLE (-1550 2350);
FORCEADD CAPP..1
(-1925 2625);
FORCEPROP 1 LAST PART_NUMBER 699013-049
J 0
(-1875 2425);
DISPLAY 0.617021 (-1875 2425);
PAINT BLUE (-1875 2425);
FORCEPROP 1 LAST PACK_TYPE 3018
J 0
(-1875 2475);
DISPLAY 0.617021 (-1875 2475);
PAINT SKYBLUE (-1875 2475);
FORCEPROP 1 LAST TOLERANCE 20%
J 0
(-1875 2625);
DISPLAY 0.617021 (-1875 2625);
PAINT SKYBLUE (-1875 2625);
FORCEPROP 1 LASTPIN (-1925 2725) $PN 1
J 0
(-1915 2710);
DISPLAY 0.617021 (-1915 2710);
PAINT GREEN (-1915 2710);
FORCEPROP 1 LAST MATERIAL ALUM
J 0
(-1875 2525);
DISPLAY 0.617021 (-1875 2525);
PAINT SKYBLUE (-1875 2525);
FORCEPROP 1 LASTPIN (-1925 2525) $PN 2
J 0
(-1915 2510);
DISPLAY 0.617021 (-1915 2510);
PAINT GREEN (-1915 2510);
FORCEPROP 1 LAST LOCATION C9P5
J 0
(-1875 2725);
DISPLAY 0.617021 (-1875 2725);
PAINT AQUA (-1875 2725);
FORCEPROP 1 LAST VALUE 470UF
J 0
(-1875 2675);
DISPLAY 0.617021 (-1875 2675);
PAINT SKYBLUE (-1875 2675);
FORCEPROP 2 LAST SEC_TYPE 3018
J 0
(-1860 2835);
DISPLAY 1.021277 (-1860 2835);
PAINT ORANGE (-1860 2835);
DISPLAY INVISIBLE (-1860 2835);
FORCEPROP 2 LAST SEC 1
J 0
(-1875 2825);
PAINT MONO (-1875 2825);
DISPLAY INVISIBLE (-1875 2825);
FORCEPROP 2 LAST BOM_COST PROC_VRD_VCCIN_CPU0
J 0
(-1875 2775);
PAINT MONO (-1875 2775);
DISPLAY INVISIBLE (-1875 2775);
FORCEPROP 1 LAST VOLTAGE 2.5V
J 0
(-1875 2575);
PAINT SKYBLUE (-1875 2575);
DISPLAY INVISIBLE (-1875 2575);
FORCEPROP 2 LAST CDS_LOCATION C9P5
J 0
(-1875 2725);
DISPLAY 0.617021 (-1875 2725);
PAINT AQUA (-1875 2725);
DISPLAY INVISIBLE (-1875 2725);
FORCEPROP 1 LAST PATH I14
J 0
(-1875 2775);
DISPLAY 0.978723 (-1875 2775);
PAINT ORANGE (-1875 2775);
DISPLAY INVISIBLE (-1875 2775);
FORCEPROP 2 LAST ROOM PVCCIN_CPU1_DECAP_VR
J 0
(-1875 2750);
PAINT MONO (-1875 2750);
DISPLAY INVISIBLE (-1875 2750);
FORCEPROP 2 LAST CDS_LIB mstr_discrete
J 0
(-1925 2625);
PAINT MONO (-1925 2625);
DISPLAY INVISIBLE (-1925 2625);
FORCEADD OFFPAGE..2
(-825 1825);
FORCEPROP 2 LAST $XR0 206 
J 0
(-636 1825);
DISPLAY 0.638298 (-636 1825);
PAINT MONO (-636 1825);
FORCEPROP 1 LAST COMMENT_BODY TRUE
J 0
(-870 1730);
DISPLAY 1.723404 (-870 1730);
PAINT GREEN (-870 1730);
DISPLAY INVISIBLE (-870 1730);
FORCEPROP 1 LAST OFFPAGE TRUE
J 0
(-500 1700);
DISPLAY 1.723404 (-500 1700);
PAINT GREEN (-500 1700);
DISPLAY INVISIBLE (-500 1700);
FORCEPROP 2 LAST BOM_COST PROC_VRD_VCCIN_CPU0
J 0
(-625 1875);
DISPLAY 1.446809 (-625 1875);
PAINT MONO (-625 1875);
DISPLAY INVISIBLE (-625 1875);
FORCEPROP 2 LAST PATH I16
J 0
(-620 1875);
DISPLAY 1.021277 (-620 1875);
PAINT ORANGE (-620 1875);
DISPLAY INVISIBLE (-620 1875);
FORCEPROP 2 LAST CDS_LIB mstr_standard
J 0
(-825 1825);
PAINT ORANGE (-825 1825);
DISPLAY INVISIBLE (-825 1825);
FORCEPROP 2 LAST ROOM PVCCIN_CPU1_PWR_VR
J 0
(-1225 1900);
DISPLAY 1.936170 (-1225 1900);
PAINT ORANGE (-1225 1900);
DISPLAY INVISIBLE (-1225 1900);
FORCEADD OFFPAGE..2
(-1675 1450);
FORCEPROP 2 LAST $XR2 209 
J 0
(-1246 1450);
DISPLAY 0.638298 (-1246 1450);
PAINT MONO (-1246 1450);
FORCEPROP 2 LAST $XR3 206 
J 0
(-1126 1450);
DISPLAY 0.638298 (-1126 1450);
PAINT MONO (-1126 1450);
FORCEPROP 2 LAST $XR0 207 
J 0
(-1486 1450);
DISPLAY 0.638298 (-1486 1450);
PAINT MONO (-1486 1450);
FORCEPROP 2 LAST $XR1 208 
J 0
(-1366 1450);
DISPLAY 0.638298 (-1366 1450);
PAINT MONO (-1366 1450);
FORCEPROP 1 LAST COMMENT_BODY TRUE
J 0
(-1720 1355);
DISPLAY 1.723404 (-1720 1355);
PAINT GREEN (-1720 1355);
DISPLAY INVISIBLE (-1720 1355);
FORCEPROP 1 LAST OFFPAGE TRUE
J 0
(-1350 1325);
DISPLAY 1.723404 (-1350 1325);
PAINT GREEN (-1350 1325);
DISPLAY INVISIBLE (-1350 1325);
FORCEPROP 2 LAST ROOM PVCCIN_CPU1_PWR_VR
J 0
(-2075 1525);
DISPLAY 1.936170 (-2075 1525);
PAINT ORANGE (-2075 1525);
DISPLAY INVISIBLE (-2075 1525);
FORCEPROP 2 LAST CDS_LIB mstr_standard
J 0
(-1675 1450);
PAINT ORANGE (-1675 1450);
DISPLAY INVISIBLE (-1675 1450);
FORCEPROP 2 LAST PATH I17
J 0
(-1245 1500);
DISPLAY 1.021277 (-1245 1500);
PAINT ORANGE (-1245 1500);
DISPLAY INVISIBLE (-1245 1500);
FORCEPROP 2 LAST BOM_COST PROC_VRD_VCCIN_CPU0
J 0
(-1475 1500);
DISPLAY 1.446809 (-1475 1500);
PAINT MONO (-1475 1500);
DISPLAY INVISIBLE (-1475 1500);
FORCEADD PVCCIN_CPU1..1
(-350 1125);
FORCEPROP 3 LASTPIN (-350 1075) SIG_NAME PVCCIN_CPU1\g
J 0
(-340 1085);
DISPLAY 0.659574 (-340 1085);
PAINT MONO (-340 1085);
DISPLAY INVISIBLE (-340 1085);
FORCEPROP 1 LAST HDL_POWER PVCCIN_CPU1
J 1
(-350 1175);
DISPLAY 0.872340 (-350 1175);
PAINT GREEN (-350 1175);
DISPLAY INVISIBLE (-350 1175);
FORCEPROP 1 LAST BODY_TYPE PLUMBING
J 0
(-395 1082);
DISPLAY 0.340426 (-395 1082);
PAINT GREEN (-395 1082);
DISPLAY INVISIBLE (-395 1082);
FORCEPROP 1 LAST VOLTAGE 2.0V
J 0
(-395 1082);
DISPLAY 0.340426 (-395 1082);
PAINT SKYBLUE (-395 1082);
DISPLAY INVISIBLE (-395 1082);
FORCEPROP 2 LAST CDS_LIB mstr_symbols
J 0
(-350 1125);
PAINT ORANGE (-350 1125);
DISPLAY INVISIBLE (-350 1125);
FORCEPROP 1 LAST PATH I18
J 0
(-300 1150);
DISPLAY 0.872340 (-300 1150);
PAINT AQUA (-300 1150);
DISPLAY INVISIBLE (-300 1150);
FORCEADD INDUCTOR..1
(-1325 1025);
FORCEPROP 1 LAST VALUE 0.12UH
J 2
(-1330 915);
DISPLAY 0.617021 (-1330 915);
PAINT SKYBLUE (-1330 915);
FORCEPROP 1 LASTPIN (-1225 1025) $PN 2
J 2
(-1215 1035);
DISPLAY 0.617021 (-1215 1035);
PAINT WHITE (-1215 1035);
FORCEPROP 1 LAST LOCATION L1D1
J 0
(-1425 1075);
DISPLAY 0.617021 (-1425 1075);
PAINT AQUA (-1425 1075);
FORCEPROP 1 LAST PACK_TYPE SM
J 0
(-1160 915);
DISPLAY 0.617021 (-1160 915);
PAINT SKYBLUE (-1160 915);
FORCEPROP 1 LASTPIN (-1425 1025) $PN 1
J 0
(-1425 1035);
DISPLAY 0.617021 (-1425 1035);
PAINT WHITE (-1425 1035);
FORCEPROP 1 LAST PART_NUMBER D92183-034
J 0
(-1450 975);
DISPLAY 0.617021 (-1450 975);
PAINT BLUE (-1450 975);
FORCEPROP 1 LAST MATERIAL IND
J 0
(-1285 915);
DISPLAY 0.617021 (-1285 915);
PAINT SKYBLUE (-1285 915);
FORCEPROP 2 LAST CDS_LIB mstr_discrete
J 0
(-1325 1025);
PAINT ORANGE (-1325 1025);
DISPLAY INVISIBLE (-1325 1025);
FORCEPROP 2 LAST ROOM PVCCIN_CPU1_PWR_VR
J 0
(-1425 1125);
DISPLAY 1.361702 (-1425 1125);
PAINT ORANGE (-1425 1125);
DISPLAY INVISIBLE (-1425 1125);
FORCEPROP 1 LAST PATH I20
J 0
(-1425 1175);
DISPLAY 0.978723 (-1425 1175);
PAINT ORANGE (-1425 1175);
DISPLAY INVISIBLE (-1425 1175);
FORCEPROP 2 LAST CDS_LOCATION L1D1
J 0
(-1425 1075);
DISPLAY 0.617021 (-1425 1075);
PAINT AQUA (-1425 1075);
DISPLAY INVISIBLE (-1425 1075);
FORCEPROP 2 LAST $SEC 1
J 0
(-1425 1225);
PAINT MONO (-1425 1225);
DISPLAY INVISIBLE (-1425 1225);
FORCEPROP 2 LAST CDS_SEC 1
J 0
(-1425 1225);
PAINT MONO (-1425 1225);
DISPLAY INVISIBLE (-1425 1225);
FORCEADD GND..1
(-350 450);
FORCEPROP 3 LASTPIN (-350 500) SIG_NAME GND\g
J 0
(-340 510);
DISPLAY 0.659574 (-340 510);
PAINT MONO (-340 510);
DISPLAY INVISIBLE (-340 510);
FORCEPROP 1 LAST HDL_POWER GND
J 0
(-350 600);
DISPLAY 1.723404 (-350 600);
PAINT GREEN (-350 600);
DISPLAY INVISIBLE (-350 600);
FORCEPROP 1 LAST BODY_TYPE PLUMBING
J 0
(-395 407);
DISPLAY 0.340426 (-395 407);
PAINT GREEN (-395 407);
DISPLAY INVISIBLE (-395 407);
FORCEPROP 1 LAST VOLTAGE 0
J 0
(-350 450);
PAINT SKYBLUE (-350 450);
DISPLAY INVISIBLE (-350 450);
FORCEPROP 1 LAST SIZE 1B
J 0
(-275 400);
DISPLAY 1.723404 (-275 400);
PAINT GREEN (-275 400);
DISPLAY INVISIBLE (-275 400);
FORCEPROP 2 LAST CDS_LIB mstr_symbols
J 0
(-350 450);
PAINT ORANGE (-350 450);
DISPLAY INVISIBLE (-350 450);
FORCEPROP 1 LAST PATH I21
J 0
(-275 450);
DISPLAY 0.872340 (-275 450);
PAINT AQUA (-275 450);
DISPLAY INVISIBLE (-275 450);
FORCEPROP 2 LAST BOM_COST PROC_VRD_VCCIN_CPU0
J 0
(-725 525);
DISPLAY 1.446809 (-725 525);
PAINT MONO (-725 525);
DISPLAY INVISIBLE (-725 525);
FORCEPROP 2 LAST ROOM PVCCIN_CPU1_PWR_VR
J 0
(-900 525);
DISPLAY 1.936170 (-900 525);
PAINT ORANGE (-900 525);
DISPLAY INVISIBLE (-900 525);
FORCEADD CAP_A..1
(-700 800);
FORCEPROP 1 LAST LOCATION C1D3
J 0
(-650 900);
DISPLAY 0.617021 (-650 900);
PAINT AQUA (-650 900);
FORCEPROP 1 LAST VALUE 22.0UF
J 0
(-650 850);
DISPLAY 0.617021 (-650 850);
PAINT SKYBLUE (-650 850);
FORCEPROP 1 LAST TOLERANCE 20%
J 0
(-650 750);
DISPLAY 0.617021 (-650 750);
PAINT SKYBLUE (-650 750);
FORCEPROP 1 LASTPIN (-700 700) $PN 2
J 0
(-690 680);
DISPLAY 0.617021 (-690 680);
PAINT ORANGE (-690 680);
FORCEPROP 1 LAST VOLTAGE 4V
J 0
(-650 800);
DISPLAY 0.617021 (-650 800);
PAINT SKYBLUE (-650 800);
FORCEPROP 1 LASTPIN (-700 900) $PN 1
J 0
(-690 880);
DISPLAY 0.617021 (-690 880);
PAINT ORANGE (-690 880);
FORCEPROP 1 LAST MATERIAL X6S
J 0
(-650 700);
DISPLAY 0.617021 (-650 700);
PAINT SKYBLUE (-650 700);
FORCEPROP 1 LAST PACK_TYPE 0603V
J 0
(-650 600);
DISPLAY 0.617021 (-650 600);
PAINT SKYBLUE (-650 600);
FORCEPROP 1 LAST PART_NUMBER E15431-004
J 0
(-650 650);
DISPLAY 0.617021 (-650 650);
PAINT BLUE (-650 650);
FORCEPROP 2 LAST SEC_TYPE 0603V
J 0
(-645 1000);
DISPLAY 1.021277 (-645 1000);
PAINT ORANGE (-645 1000);
DISPLAY INVISIBLE (-645 1000);
FORCEPROP 2 LAST SEC 1
J 0
(-645 1000);
DISPLAY 0.680851 (-645 1000);
PAINT MONO (-645 1000);
DISPLAY INVISIBLE (-645 1000);
FORCEPROP 2 LAST BOM_COST PROC_VRD_VCCIN_CPU0
J 0
(-650 950);
DISPLAY 1.446809 (-650 950);
PAINT MONO (-650 950);
DISPLAY INVISIBLE (-650 950);
FORCEPROP 2 LAST CDS_LOCATION C1D3
J 0
(-650 900);
DISPLAY 0.617021 (-650 900);
PAINT AQUA (-650 900);
DISPLAY INVISIBLE (-650 900);
FORCEPROP 2 LAST CDS_SEC 1
J 0
(-650 950);
PAINT ORANGE (-650 950);
DISPLAY INVISIBLE (-650 950);
FORCEPROP 1 LAST PATH I22
J 0
(-650 950);
DISPLAY 0.978723 (-650 950);
PAINT WHITE (-650 950);
DISPLAY INVISIBLE (-650 950);
FORCEPROP 2 LAST ROOM PVCCIN_CPU1_PWR_VR
J 0
(-650 950);
DISPLAY 1.446809 (-650 950);
PAINT MONO (-650 950);
DISPLAY INVISIBLE (-650 950);
FORCEPROP 2 LAST CDS_LIB dev_discrete
J 0
(-700 800);
PAINT ORANGE (-700 800);
DISPLAY INVISIBLE (-700 800);
FORCEADD GND..1
(-2600 3175);
FORCEPROP 3 LASTPIN (-2600 3225) SIG_NAME GND\g
J 0
(-2590 3235);
DISPLAY 0.659574 (-2590 3235);
PAINT MONO (-2590 3235);
DISPLAY INVISIBLE (-2590 3235);
FORCEPROP 1 LAST HDL_POWER GND
J 0
(-2600 3325);
DISPLAY 1.723404 (-2600 3325);
PAINT GREEN (-2600 3325);
DISPLAY INVISIBLE (-2600 3325);
FORCEPROP 1 LAST BODY_TYPE PLUMBING
J 0
(-2645 3132);
DISPLAY 0.340426 (-2645 3132);
PAINT GREEN (-2645 3132);
DISPLAY INVISIBLE (-2645 3132);
FORCEPROP 1 LAST SIZE 1B
J 0
(-2525 3125);
DISPLAY 1.723404 (-2525 3125);
PAINT GREEN (-2525 3125);
DISPLAY INVISIBLE (-2525 3125);
FORCEPROP 1 LAST PATH I23
J 0
(-2525 3175);
DISPLAY 0.872340 (-2525 3175);
PAINT AQUA (-2525 3175);
DISPLAY INVISIBLE (-2525 3175);
FORCEPROP 1 LAST VOLTAGE 0
J 0
(-2600 3175);
PAINT SKYBLUE (-2600 3175);
DISPLAY INVISIBLE (-2600 3175);
FORCEPROP 2 LAST CDS_LIB mstr_symbols
J 0
(-2600 3175);
DISPLAY 1.936170 (-2600 3175);
PAINT ORANGE (-2600 3175);
DISPLAY INVISIBLE (-2600 3175);
FORCEPROP 2 LAST BOM_COST PROC_VRD_VCCIN_CPU0
J 0
(-2975 3250);
DISPLAY 1.446809 (-2975 3250);
PAINT MONO (-2975 3250);
DISPLAY INVISIBLE (-2975 3250);
FORCEPROP 2 LAST ROOM PVCCIN_CPU1_PWR_VR
J 0
(-3150 3250);
DISPLAY 1.936170 (-3150 3250);
PAINT ORANGE (-3150 3250);
DISPLAY INVISIBLE (-3150 3250);
FORCEADD CAPP..1
(-2375 2600);
FORCEPROP 1 LAST LOCATION C9N24
J 0
(-2325 2700);
DISPLAY 0.617021 (-2325 2700);
PAINT AQUA (-2325 2700);
FORCEPROP 1 LAST PART_NUMBER 699013-049
J 0
(-2325 2400);
DISPLAY 0.617021 (-2325 2400);
PAINT BLUE (-2325 2400);
FORCEPROP 1 LASTPIN (-2375 2500) $PN 2
J 0
(-2365 2485);
DISPLAY 0.617021 (-2365 2485);
PAINT GREEN (-2365 2485);
FORCEPROP 1 LAST TOLERANCE 20%
J 0
(-2325 2600);
DISPLAY 0.617021 (-2325 2600);
PAINT SKYBLUE (-2325 2600);
FORCEPROP 1 LAST MATERIAL ALUM
J 0
(-2325 2500);
DISPLAY 0.617021 (-2325 2500);
PAINT SKYBLUE (-2325 2500);
FORCEPROP 1 LAST PACK_TYPE 3018
J 0
(-2325 2450);
DISPLAY 0.617021 (-2325 2450);
PAINT SKYBLUE (-2325 2450);
FORCEPROP 1 LASTPIN (-2375 2700) $PN 1
J 0
(-2365 2685);
DISPLAY 0.617021 (-2365 2685);
PAINT GREEN (-2365 2685);
FORCEPROP 1 LAST VALUE 470UF
J 0
(-2325 2650);
DISPLAY 0.617021 (-2325 2650);
PAINT SKYBLUE (-2325 2650);
FORCEPROP 2 LAST SEC_TYPE 3018
J 0
(-2310 2810);
DISPLAY 1.021277 (-2310 2810);
PAINT ORANGE (-2310 2810);
DISPLAY INVISIBLE (-2310 2810);
FORCEPROP 2 LAST SEC 1
J 0
(-2325 2800);
PAINT MONO (-2325 2800);
DISPLAY INVISIBLE (-2325 2800);
FORCEPROP 2 LAST BOM_COST PROC_VRD_VCCIN_CPU0
J 0
(-2325 2750);
PAINT MONO (-2325 2750);
DISPLAY INVISIBLE (-2325 2750);
FORCEPROP 2 LAST CDS_LOCATION C9N24
J 0
(-2325 2700);
DISPLAY 0.617021 (-2325 2700);
PAINT AQUA (-2325 2700);
DISPLAY INVISIBLE (-2325 2700);
FORCEPROP 1 LAST PATH I24
J 0
(-2325 2750);
DISPLAY 0.978723 (-2325 2750);
PAINT ORANGE (-2325 2750);
DISPLAY INVISIBLE (-2325 2750);
FORCEPROP 2 LAST ROOM PVCCIN_CPU1_DECAP_VR
J 0
(-2325 2725);
PAINT MONO (-2325 2725);
DISPLAY INVISIBLE (-2325 2725);
FORCEPROP 2 LAST CDS_LIB mstr_discrete
J 0
(-2375 2600);
PAINT MONO (-2375 2600);
DISPLAY INVISIBLE (-2375 2600);
FORCEPROP 1 LAST VOLTAGE 2.5V
J 0
(-2325 2550);
PAINT SKYBLUE (-2325 2550);
DISPLAY INVISIBLE (-2325 2550);
FORCEADD CAPP..1
(-2825 2625);
FORCEPROP 1 LAST TOLERANCE 20%
J 0
(-2775 2625);
DISPLAY 0.617021 (-2775 2625);
PAINT SKYBLUE (-2775 2625);
FORCEPROP 1 LAST LOCATION C9R9
J 0
(-2775 2725);
DISPLAY 0.617021 (-2775 2725);
PAINT AQUA (-2775 2725);
FORCEPROP 1 LAST VALUE 470UF
J 0
(-2775 2675);
DISPLAY 0.617021 (-2775 2675);
PAINT SKYBLUE (-2775 2675);
FORCEPROP 1 LASTPIN (-2825 2725) $PN 1
J 0
(-2815 2710);
DISPLAY 0.617021 (-2815 2710);
PAINT GREEN (-2815 2710);
FORCEPROP 1 LAST MATERIAL ALUM
J 0
(-2775 2525);
DISPLAY 0.617021 (-2775 2525);
PAINT SKYBLUE (-2775 2525);
FORCEPROP 1 LASTPIN (-2825 2525) $PN 2
J 0
(-2815 2510);
DISPLAY 0.617021 (-2815 2510);
PAINT GREEN (-2815 2510);
FORCEPROP 1 LAST PART_NUMBER 699013-049
J 0
(-2775 2425);
DISPLAY 0.617021 (-2775 2425);
PAINT BLUE (-2775 2425);
FORCEPROP 1 LAST PACK_TYPE 3018
J 0
(-2775 2475);
DISPLAY 0.617021 (-2775 2475);
PAINT SKYBLUE (-2775 2475);
FORCEPROP 2 LAST SEC 1
J 0
(-2775 2825);
PAINT MONO (-2775 2825);
DISPLAY INVISIBLE (-2775 2825);
FORCEPROP 2 LAST SEC_TYPE 3018
J 0
(-2760 2835);
DISPLAY 1.021277 (-2760 2835);
PAINT ORANGE (-2760 2835);
DISPLAY INVISIBLE (-2760 2835);
FORCEPROP 2 LAST BOM_COST PROC_VRD_VCCIN_CPU0
J 0
(-2775 2775);
PAINT MONO (-2775 2775);
DISPLAY INVISIBLE (-2775 2775);
FORCEPROP 2 LAST ROOM PVCCIN_CPU1_DECAP_VR
J 0
(-2775 2750);
PAINT MONO (-2775 2750);
DISPLAY INVISIBLE (-2775 2750);
FORCEPROP 1 LAST PATH I25
J 0
(-2775 2775);
DISPLAY 0.978723 (-2775 2775);
PAINT ORANGE (-2775 2775);
DISPLAY INVISIBLE (-2775 2775);
FORCEPROP 2 LAST CDS_LOCATION C9R9
J 0
(-2775 2725);
DISPLAY 0.617021 (-2775 2725);
PAINT AQUA (-2775 2725);
DISPLAY INVISIBLE (-2775 2725);
FORCEPROP 1 LAST VOLTAGE 2.5V
J 0
(-2775 2575);
PAINT SKYBLUE (-2775 2575);
DISPLAY INVISIBLE (-2775 2575);
FORCEPROP 2 LAST CDS_LIB mstr_discrete
J 0
(-2825 2625);
PAINT MONO (-2825 2625);
DISPLAY INVISIBLE (-2825 2625);
FORCEADD CAPP..1
(-3275 2625);
FORCEPROP 1 LAST PACK_TYPE 3018
J 0
(-3225 2475);
DISPLAY 0.617021 (-3225 2475);
PAINT SKYBLUE (-3225 2475);
FORCEPROP 1 LAST PART_NUMBER 699013-049
J 0
(-3225 2425);
DISPLAY 0.617021 (-3225 2425);
PAINT BLUE (-3225 2425);
FORCEPROP 1 LAST LOCATION C9R3
J 0
(-3225 2725);
DISPLAY 0.617021 (-3225 2725);
PAINT AQUA (-3225 2725);
FORCEPROP 1 LAST VALUE 470UF
J 0
(-3225 2675);
DISPLAY 0.617021 (-3225 2675);
PAINT SKYBLUE (-3225 2675);
FORCEPROP 1 LAST TOLERANCE 20%
J 0
(-3225 2625);
DISPLAY 0.617021 (-3225 2625);
PAINT SKYBLUE (-3225 2625);
FORCEPROP 1 LASTPIN (-3275 2725) $PN 1
J 0
(-3265 2710);
DISPLAY 0.617021 (-3265 2710);
PAINT GREEN (-3265 2710);
FORCEPROP 1 LASTPIN (-3275 2525) $PN 2
J 0
(-3265 2510);
DISPLAY 0.617021 (-3265 2510);
PAINT GREEN (-3265 2510);
FORCEPROP 1 LAST MATERIAL ALUM
J 0
(-3225 2525);
DISPLAY 0.617021 (-3225 2525);
PAINT SKYBLUE (-3225 2525);
FORCEPROP 2 LAST SEC_TYPE 3018
J 0
(-3210 2835);
DISPLAY 1.021277 (-3210 2835);
PAINT ORANGE (-3210 2835);
DISPLAY INVISIBLE (-3210 2835);
FORCEPROP 2 LAST SEC 1
J 0
(-3225 2825);
PAINT MONO (-3225 2825);
DISPLAY INVISIBLE (-3225 2825);
FORCEPROP 2 LAST BOM_COST PROC_VRD_VCCIN_CPU0
J 0
(-3225 2775);
PAINT MONO (-3225 2775);
DISPLAY INVISIBLE (-3225 2775);
FORCEPROP 2 LAST CDS_LOCATION C9R3
J 0
(-3225 2725);
DISPLAY 0.617021 (-3225 2725);
PAINT AQUA (-3225 2725);
DISPLAY INVISIBLE (-3225 2725);
FORCEPROP 1 LAST PATH I26
J 0
(-3225 2775);
DISPLAY 0.978723 (-3225 2775);
PAINT ORANGE (-3225 2775);
DISPLAY INVISIBLE (-3225 2775);
FORCEPROP 2 LAST ROOM PVCCIN_CPU1_DECAP_VR
J 0
(-3225 2750);
PAINT MONO (-3225 2750);
DISPLAY INVISIBLE (-3225 2750);
FORCEPROP 1 LAST VOLTAGE 2.5V
J 0
(-3225 2575);
PAINT SKYBLUE (-3225 2575);
DISPLAY INVISIBLE (-3225 2575);
FORCEPROP 2 LAST CDS_LIB mstr_discrete
J 0
(-3275 2625);
PAINT MONO (-3275 2625);
DISPLAY INVISIBLE (-3275 2625);
FORCEADD IR354XX..1
(-3300 3875);
FORCEPROP 2 LASTPIN (-3800 3525) $PN 32
J 2
(-3810 3535);
DISPLAY 0.617021 (-3810 3535);
PAINT ORANGE (-3810 3535);
FORCEPROP 2 LASTPIN (-2800 4225) $PN 37
J 0
(-2790 4235);
DISPLAY 0.617021 (-2790 4235);
PAINT ORANGE (-2790 4235);
FORCEPROP 2 LASTPIN (-2800 4175) $PN 31
J 0
(-2790 4185);
DISPLAY 0.617021 (-2790 4185);
PAINT ORANGE (-2790 4185);
FORCEPROP 2 LASTPIN (-2800 4425) $PN 38
J 0
(-2790 4435);
DISPLAY 0.617021 (-2790 4435);
PAINT ORANGE (-2790 4435);
FORCEPROP 1 LAST VALUE IR35411
J 1
(-3300 4500);
DISPLAY 0.617021 (-3300 4500);
PAINT SKYBLUE (-3300 4500);
FORCEPROP 1 LAST LOCATION EU1D3
J 0
(-3525 4675);
DISPLAY 0.617021 (-3525 4675);
PAINT AQUA (-3525 4675);
FORCEPROP 1 LAST MATERIAL IC
J 0
(-3750 4625);
DISPLAY 0.617021 (-3750 4625);
PAINT SKYBLUE (-3750 4625);
FORCEPROP 2 LASTPIN (-3800 4425) $PN 3
J 2
(-3810 4435);
DISPLAY 0.617021 (-3810 4435);
PAINT ORANGE (-3810 4435);
FORCEPROP 2 LASTPIN (-3800 4225) $PN 4
J 2
(-3810 4235);
DISPLAY 0.617021 (-3810 4235);
PAINT ORANGE (-3810 4235);
FORCEPROP 2 LASTPIN (-3800 4325) $PN 25
J 2
(-3810 4335);
DISPLAY 0.617021 (-3810 4335);
PAINT ORANGE (-3810 4335);
FORCEPROP 2 LASTPIN (-3800 4375) $PN 30
J 2
(-3810 4385);
DISPLAY 0.617021 (-3810 4385);
PAINT ORANGE (-3810 4385);
FORCEPROP 2 LASTPIN (-2800 3925) $PN 36
J 0
(-2790 3935);
DISPLAY 0.617021 (-2790 3935);
PAINT ORANGE (-2790 3935);
FORCEPROP 2 LASTPIN (-2800 3575) $PN 10
J 0
(-2790 3585);
DISPLAY 0.617021 (-2790 3585);
PAINT ORANGE (-2790 3585);
FORCEPROP 2 LASTPIN (-2800 3475) $PN 2
J 0
(-2790 3485);
DISPLAY 0.617021 (-2790 3485);
PAINT ORANGE (-2790 3485);
FORCEPROP 2 LASTPIN (-2800 3325) $PN 5
J 0
(-2790 3335);
DISPLAY 0.617021 (-2790 3335);
PAINT ORANGE (-2790 3335);
FORCEPROP 2 LASTPIN (-2800 3425) $PN 40
J 0
(-2790 3435);
DISPLAY 0.617021 (-2790 3435);
PAINT ORANGE (-2790 3435);
FORCEPROP 2 LASTPIN (-3800 3875) $PN 6
J 2
(-3810 3885);
DISPLAY 0.617021 (-3810 3885);
PAINT ORANGE (-3810 3885);
FORCEPROP 2 LASTPIN (-3800 4025) $PN 1
J 2
(-3810 4035);
DISPLAY 0.617021 (-3810 4035);
PAINT ORANGE (-3810 4035);
FORCEPROP 2 LASTPIN (-3800 3775) $PN 34
J 2
(-3810 3785);
DISPLAY 0.617021 (-3810 3785);
PAINT ORANGE (-3810 3785);
FORCEPROP 2 LASTPIN (-3800 3925) $PN 41
J 2
(-3810 3935);
DISPLAY 0.617021 (-3810 3935);
PAINT ORANGE (-3810 3935);
FORCEPROP 2 LASTPIN (-2800 3375) $PN 7
J 0
(-2790 3385);
DISPLAY 0.617021 (-2790 3385);
PAINT ORANGE (-2790 3385);
FORCEPROP 2 LASTPIN (-3800 4125) $PN 35
J 2
(-3810 4135);
DISPLAY 0.617021 (-3810 4135);
PAINT ORANGE (-3810 4135);
FORCEPROP 2 LASTPIN (-3800 3675) $PN 39
J 2
(-3810 3685);
DISPLAY 0.617021 (-3810 3685);
PAINT ORANGE (-3810 3685);
FORCEPROP 2 LASTPIN (-3800 3575) $PN 33
J 2
(-3810 3585);
DISPLAY 0.617021 (-3810 3585);
PAINT ORANGE (-3810 3585);
FORCEPROP 1 LAST PART_NUMBER H73688-001
J 0
(-3650 3175);
DISPLAY 0.617021 (-3650 3175);
PAINT BLUE (-3650 3175);
FORCEPROP 2 LAST SEC 1
J 0
(-3300 4675);
DISPLAY 0.680851 (-3300 4675);
PAINT MONO (-3300 4675);
DISPLAY INVISIBLE (-3300 4675);
FORCEPROP 2 LAST SEC_TYPE SM
J 0
(-3300 4675);
DISPLAY 1.021277 (-3300 4675);
PAINT ORANGE (-3300 4675);
DISPLAY INVISIBLE (-3300 4675);
FORCEPROP 2 LAST CDS_LOCATION EU1D3
J 0
(-3525 4675);
DISPLAY 0.617021 (-3525 4675);
PAINT AQUA (-3525 4675);
DISPLAY INVISIBLE (-3525 4675);
FORCEPROP 1 LAST PATH I27
J 0
(-3300 4625);
PAINT GREEN (-3300 4625);
DISPLAY INVISIBLE (-3300 4625);
FORCEPROP 1 LAST PACK_TYPE SM
J 0
(-3750 4725);
PAINT SKYBLUE (-3750 4725);
DISPLAY INVISIBLE (-3750 4725);
FORCEPROP 2 LAST CDS_LIB mstr_discrete
J 0
(-3300 3875);
PAINT ORANGE (-3300 3875);
DISPLAY INVISIBLE (-3300 3875);
FORCEPROP 2 LAST ROOM PVCCIN_CPU1_PWR_VR
J 0
(-5025 2150);
DISPLAY 1.361702 (-5025 2150);
PAINT ORANGE (-5025 2150);
DISPLAY INVISIBLE (-5025 2150);
FORCEADD CAPP..1
(-3725 2625);
FORCEPROP 1 LAST PART_NUMBER 699013-049
J 0
(-3675 2425);
DISPLAY 0.617021 (-3675 2425);
PAINT BLUE (-3675 2425);
FORCEPROP 1 LAST PACK_TYPE 3018
J 0
(-3675 2475);
DISPLAY 0.617021 (-3675 2475);
PAINT SKYBLUE (-3675 2475);
FORCEPROP 1 LAST MATERIAL ALUM
J 0
(-3675 2525);
DISPLAY 0.617021 (-3675 2525);
PAINT SKYBLUE (-3675 2525);
FORCEPROP 1 LAST TOLERANCE 20%
J 0
(-3675 2625);
DISPLAY 0.617021 (-3675 2625);
PAINT SKYBLUE (-3675 2625);
FORCEPROP 1 LAST VALUE 470UF
J 0
(-3675 2675);
DISPLAY 0.617021 (-3675 2675);
PAINT SKYBLUE (-3675 2675);
FORCEPROP 1 LAST LOCATION C9P23
J 0
(-3675 2725);
DISPLAY 0.617021 (-3675 2725);
PAINT AQUA (-3675 2725);
FORCEPROP 1 LASTPIN (-3725 2725) $PN 1
J 0
(-3715 2710);
DISPLAY 0.617021 (-3715 2710);
PAINT GREEN (-3715 2710);
FORCEPROP 1 LASTPIN (-3725 2525) $PN 2
J 0
(-3715 2510);
DISPLAY 0.617021 (-3715 2510);
PAINT GREEN (-3715 2510);
FORCEPROP 2 LAST SEC_TYPE 3018
J 0
(-3660 2835);
DISPLAY 1.021277 (-3660 2835);
PAINT ORANGE (-3660 2835);
DISPLAY INVISIBLE (-3660 2835);
FORCEPROP 2 LAST SEC 1
J 0
(-3675 2825);
PAINT MONO (-3675 2825);
DISPLAY INVISIBLE (-3675 2825);
FORCEPROP 2 LAST BOM_COST PROC_VRD_VCCIN_CPU0
J 0
(-3675 2775);
PAINT MONO (-3675 2775);
DISPLAY INVISIBLE (-3675 2775);
FORCEPROP 1 LAST VOLTAGE 2.5V
J 0
(-3675 2575);
PAINT SKYBLUE (-3675 2575);
DISPLAY INVISIBLE (-3675 2575);
FORCEPROP 2 LAST CDS_LOCATION C9P23
J 0
(-3675 2725);
DISPLAY 0.617021 (-3675 2725);
PAINT AQUA (-3675 2725);
DISPLAY INVISIBLE (-3675 2725);
FORCEPROP 1 LAST PATH I28
J 0
(-3675 2775);
DISPLAY 0.978723 (-3675 2775);
PAINT ORANGE (-3675 2775);
DISPLAY INVISIBLE (-3675 2775);
FORCEPROP 2 LAST ROOM PVCCIN_CPU1_DECAP_VR
J 0
(-3675 2750);
PAINT MONO (-3675 2750);
DISPLAY INVISIBLE (-3675 2750);
FORCEPROP 2 LAST CDS_LIB mstr_discrete
J 0
(-3725 2625);
PAINT MONO (-3725 2625);
DISPLAY INVISIBLE (-3725 2625);
FORCEADD PVCCIN_CPU1..1
(-4250 2900);
FORCEPROP 3 LASTPIN (-4250 2850) SIG_NAME PVCCIN_CPU1\g
J 0
(-4240 2860);
DISPLAY 0.659574 (-4240 2860);
PAINT MONO (-4240 2860);
DISPLAY INVISIBLE (-4240 2860);
FORCEPROP 1 LAST PATH I29
J 0
(-4200 2925);
DISPLAY 0.872340 (-4200 2925);
PAINT AQUA (-4200 2925);
DISPLAY INVISIBLE (-4200 2925);
FORCEPROP 2 LAST CDS_LIB mstr_symbols
J 0
(-4250 2900);
PAINT ORANGE (-4250 2900);
DISPLAY INVISIBLE (-4250 2900);
FORCEPROP 1 LAST VOLTAGE 2.0V
J 0
(-4295 2857);
DISPLAY 0.340426 (-4295 2857);
PAINT SKYBLUE (-4295 2857);
DISPLAY INVISIBLE (-4295 2857);
FORCEPROP 1 LAST BODY_TYPE PLUMBING
J 0
(-4295 2857);
DISPLAY 0.340426 (-4295 2857);
PAINT GREEN (-4295 2857);
DISPLAY INVISIBLE (-4295 2857);
FORCEPROP 1 LAST HDL_POWER PVCCIN_CPU1
J 1
(-4250 2950);
DISPLAY 0.872340 (-4250 2950);
PAINT GREEN (-4250 2950);
DISPLAY INVISIBLE (-4250 2950);
FORCEADD OFFPAGE..2
(-1525 4050);
FORCEPROP 2 LAST $XR0 207 
J 0
(-1336 4050);
DISPLAY 0.638298 (-1336 4050);
PAINT MONO (-1336 4050);
FORCEPROP 2 LAST $XR1 208 
J 0
(-1216 4050);
DISPLAY 0.638298 (-1216 4050);
PAINT MONO (-1216 4050);
FORCEPROP 2 LAST $XR2 209 
J 0
(-1096 4050);
DISPLAY 0.638298 (-1096 4050);
PAINT MONO (-1096 4050);
FORCEPROP 2 LAST $XR3 206 
J 0
(-976 4050);
DISPLAY 0.638298 (-976 4050);
PAINT MONO (-976 4050);
FORCEPROP 1 LAST COMMENT_BODY TRUE
J 0
(-1570 3955);
DISPLAY 1.723404 (-1570 3955);
PAINT GREEN (-1570 3955);
DISPLAY INVISIBLE (-1570 3955);
FORCEPROP 1 LAST OFFPAGE TRUE
J 0
(-1200 3925);
DISPLAY 1.723404 (-1200 3925);
PAINT GREEN (-1200 3925);
DISPLAY INVISIBLE (-1200 3925);
FORCEPROP 2 LAST ROOM PVCCIN_CPU1_PWR_VR
J 0
(-1925 4125);
DISPLAY 1.936170 (-1925 4125);
PAINT ORANGE (-1925 4125);
DISPLAY INVISIBLE (-1925 4125);
FORCEPROP 2 LAST CDS_LIB mstr_standard
J 0
(-1525 4050);
PAINT ORANGE (-1525 4050);
DISPLAY INVISIBLE (-1525 4050);
FORCEPROP 2 LAST BOM_COST PROC_VRD_VCCIN_CPU0
J 0
(-1325 4100);
DISPLAY 1.446809 (-1325 4100);
PAINT MONO (-1325 4100);
DISPLAY INVISIBLE (-1325 4100);
FORCEPROP 2 LAST PATH I3
J 0
(-1095 4100);
DISPLAY 1.021277 (-1095 4100);
PAINT ORANGE (-1095 4100);
DISPLAY INVISIBLE (-1095 4100);
FORCEADD CAPP..1
(-4150 2625);
FORCEPROP 1 LAST VOLTAGE 2.5V
J 0
(-4100 2575);
DISPLAY 0.617021 (-4100 2575);
PAINT SKYBLUE (-4100 2575);
FORCEPROP 1 LAST TOLERANCE 20%
J 0
(-4100 2625);
DISPLAY 0.617021 (-4100 2625);
PAINT SKYBLUE (-4100 2625);
FORCEPROP 1 LAST PART_NUMBER 699013-049
J 0
(-4100 2425);
DISPLAY 0.617021 (-4100 2425);
PAINT BLUE (-4100 2425);
FORCEPROP 1 LAST PACK_TYPE 3018
J 0
(-4100 2475);
DISPLAY 0.617021 (-4100 2475);
PAINT SKYBLUE (-4100 2475);
FORCEPROP 1 LAST MATERIAL ALUM
J 0
(-4100 2525);
DISPLAY 0.617021 (-4100 2525);
PAINT SKYBLUE (-4100 2525);
FORCEPROP 1 LASTPIN (-4150 2525) $PN 2
J 0
(-4140 2510);
DISPLAY 0.617021 (-4140 2510);
PAINT GREEN (-4140 2510);
FORCEPROP 1 LASTPIN (-4150 2725) $PN 1
J 0
(-4140 2710);
DISPLAY 0.617021 (-4140 2710);
PAINT GREEN (-4140 2710);
FORCEPROP 1 LAST LOCATION C9P18
J 0
(-4100 2725);
DISPLAY 0.617021 (-4100 2725);
PAINT AQUA (-4100 2725);
FORCEPROP 1 LAST VALUE 470UF
J 0
(-4100 2675);
DISPLAY 0.617021 (-4100 2675);
PAINT SKYBLUE (-4100 2675);
FORCEPROP 2 LAST SEC_TYPE 3018
J 0
(-4085 2835);
DISPLAY 1.021277 (-4085 2835);
PAINT ORANGE (-4085 2835);
DISPLAY INVISIBLE (-4085 2835);
FORCEPROP 2 LAST SEC 1
J 0
(-4100 2825);
PAINT MONO (-4100 2825);
DISPLAY INVISIBLE (-4100 2825);
FORCEPROP 2 LAST BOM_COST PROC_VRD_VCCIN_CPU0
J 0
(-4100 2775);
PAINT MONO (-4100 2775);
DISPLAY INVISIBLE (-4100 2775);
FORCEPROP 2 LAST CDS_LOCATION C9P18
J 0
(-4100 2725);
DISPLAY 0.617021 (-4100 2725);
PAINT AQUA (-4100 2725);
DISPLAY INVISIBLE (-4100 2725);
FORCEPROP 1 LAST PATH I30
J 0
(-4100 2775);
DISPLAY 0.978723 (-4100 2775);
PAINT ORANGE (-4100 2775);
DISPLAY INVISIBLE (-4100 2775);
FORCEPROP 2 LAST ROOM PVCCIN_CPU1_DECAP_VR
J 0
(-4100 2750);
PAINT MONO (-4100 2750);
DISPLAY INVISIBLE (-4100 2750);
FORCEPROP 2 LAST CDS_LIB mstr_discrete
J 0
(-4150 2625);
PAINT MONO (-4150 2625);
DISPLAY INVISIBLE (-4150 2625);
FORCEADD GND..1
(-2575 600);
FORCEPROP 3 LASTPIN (-2575 650) SIG_NAME GND\g
J 0
(-2565 660);
DISPLAY 0.659574 (-2565 660);
PAINT MONO (-2565 660);
DISPLAY INVISIBLE (-2565 660);
FORCEPROP 1 LAST HDL_POWER GND
J 0
(-2575 750);
DISPLAY 1.723404 (-2575 750);
PAINT GREEN (-2575 750);
DISPLAY INVISIBLE (-2575 750);
FORCEPROP 1 LAST BODY_TYPE PLUMBING
J 0
(-2620 557);
DISPLAY 0.340426 (-2620 557);
PAINT GREEN (-2620 557);
DISPLAY INVISIBLE (-2620 557);
FORCEPROP 1 LAST SIZE 1B
J 0
(-2500 550);
DISPLAY 1.723404 (-2500 550);
PAINT GREEN (-2500 550);
DISPLAY INVISIBLE (-2500 550);
FORCEPROP 1 LAST PATH I33
J 0
(-2500 600);
DISPLAY 0.872340 (-2500 600);
PAINT AQUA (-2500 600);
DISPLAY INVISIBLE (-2500 600);
FORCEPROP 1 LAST VOLTAGE 0
J 0
(-2575 600);
PAINT SKYBLUE (-2575 600);
DISPLAY INVISIBLE (-2575 600);
FORCEPROP 2 LAST CDS_LIB mstr_symbols
J 0
(-2575 600);
PAINT ORANGE (-2575 600);
DISPLAY INVISIBLE (-2575 600);
FORCEPROP 2 LAST BOM_COST PROC_VRD_VCCIN_CPU0
J 0
(-2950 675);
DISPLAY 1.446809 (-2950 675);
PAINT MONO (-2950 675);
DISPLAY INVISIBLE (-2950 675);
FORCEPROP 2 LAST ROOM PVCCIN_CPU1_PWR_VR
J 0
(-3125 675);
DISPLAY 1.936170 (-3125 675);
PAINT ORANGE (-3125 675);
DISPLAY INVISIBLE (-3125 675);
FORCEADD RES..1
(-5275 4700);
FORCEPROP 1 LAST WATTAGE 1/16W
J 2
(-5250 4525);
DISPLAY 0.617021 (-5250 4525);
PAINT SKYBLUE (-5250 4525);
FORCEPROP 1 LAST VALUE 1.0
J 2
(-5375 4575);
DISPLAY 0.617021 (-5375 4575);
PAINT SKYBLUE (-5375 4575);
FORCEPROP 1 LAST TOLERANCE 1%
J 0
(-5325 4575);
DISPLAY 0.617021 (-5325 4575);
PAINT SKYBLUE (-5325 4575);
FORCEPROP 1 LASTPIN (-5375 4700) $PN 1
J 0
(-5363 4712);
DISPLAY 0.617021 (-5363 4712);
PAINT ORANGE (-5363 4712);
FORCEPROP 1 LAST LOCATION R9P22
J 0
(-5325 4750);
DISPLAY 0.617021 (-5325 4750);
PAINT AQUA (-5325 4750);
FORCEPROP 1 LASTPIN (-5175 4700) $PN 2
J 0
(-5213 4712);
DISPLAY 0.617021 (-5213 4712);
PAINT ORANGE (-5213 4712);
FORCEPROP 1 LAST MATERIAL CHIP
J 0
(-5200 4525);
DISPLAY 0.617021 (-5200 4525);
PAINT SKYBLUE (-5200 4525);
FORCEPROP 1 LAST PACK_TYPE 0402
J 0
(-5225 4575);
DISPLAY 0.617021 (-5225 4575);
PAINT SKYBLUE (-5225 4575);
FORCEPROP 1 LAST PART_NUMBER G21796-090
J 0
(-5400 4625);
DISPLAY 0.617021 (-5400 4625);
PAINT BLUE (-5400 4625);
FORCEPROP 2 LAST CDS_LIB mstr_discrete
J 0
(-5275 4700);
PAINT ORANGE (-5275 4700);
DISPLAY INVISIBLE (-5275 4700);
FORCEPROP 2 LAST CDS_LOCATION R9P22
J 0
(-5325 4750);
DISPLAY 0.617021 (-5325 4750);
PAINT AQUA (-5325 4750);
DISPLAY INVISIBLE (-5325 4750);
FORCEPROP 2 LAST ROOM PVCCIN_CPU1_PWR_VR
J 0
(-5325 4800);
DISPLAY 1.361702 (-5325 4800);
PAINT ORANGE (-5325 4800);
DISPLAY INVISIBLE (-5325 4800);
FORCEPROP 1 LAST PATH I36
J 0
(-5325 4850);
DISPLAY 0.978723 (-5325 4850);
PAINT WHITE (-5325 4850);
DISPLAY INVISIBLE (-5325 4850);
FORCEPROP 2 LAST SEC 1
J 0
(-5325 4900);
DISPLAY 0.680851 (-5325 4900);
PAINT MONO (-5325 4900);
DISPLAY INVISIBLE (-5325 4900);
FORCEPROP 2 LAST SEC_TYPE 0402
J 0
(-5325 4900);
DISPLAY 1.021277 (-5325 4900);
PAINT ORANGE (-5325 4900);
DISPLAY INVISIBLE (-5325 4900);
FORCEADD VCC_CORE..1
(-7425 4525);
FORCEPROP 3 LASTPIN (-7425 4475) SIG_NAME VR_FET_SW_P12V_STBY_PVCCIN_CPU1\g
J 0
(-7415 4485);
DISPLAY 0.659574 (-7415 4485);
PAINT MONO (-7415 4485);
DISPLAY INVISIBLE (-7415 4485);
FORCEPROP 1 LAST HDL_POWER VR_FET_SW_P12V_STBY_PVCCIN_CPU1
J 1
(-7325 4575);
DISPLAY 0.617021 (-7325 4575);
PAINT GREEN (-7325 4575);
FORCEPROP 1 LAST PATH I37
J 0
(-7375 4550);
DISPLAY 0.872340 (-7375 4550);
PAINT AQUA (-7375 4550);
DISPLAY INVISIBLE (-7375 4550);
FORCEPROP 2 LAST CDS_LIB mstr_symbols
J 0
(-7425 4525);
DISPLAY 1.936170 (-7425 4525);
PAINT ORANGE (-7425 4525);
DISPLAY INVISIBLE (-7425 4525);
FORCEADD CAP..1
(-4850 4200);
FORCEPROP 1 LAST PART_NUMBER A36096-155
J 0
(-4800 4050);
DISPLAY 0.617021 (-4800 4050);
PAINT BLUE (-4800 4050);
FORCEPROP 1 LAST PACK_TYPE 0402
J 0
(-4800 4000);
DISPLAY 0.617021 (-4800 4000);
PAINT SKYBLUE (-4800 4000);
FORCEPROP 1 LASTPIN (-4850 4300) $PN 1
J 0
(-4840 4280);
DISPLAY 0.617021 (-4840 4280);
PAINT ORANGE (-4840 4280);
FORCEPROP 1 LAST MATERIAL X7R
J 0
(-4800 4100);
DISPLAY 0.617021 (-4800 4100);
PAINT SKYBLUE (-4800 4100);
FORCEPROP 1 LAST VOLTAGE 16V
J 0
(-4800 4200);
DISPLAY 0.617021 (-4800 4200);
PAINT SKYBLUE (-4800 4200);
FORCEPROP 1 LAST TOLERANCE 10%
J 0
(-4800 4150);
DISPLAY 0.617021 (-4800 4150);
PAINT SKYBLUE (-4800 4150);
FORCEPROP 1 LAST VALUE 0.22UF
J 0
(-4800 4250);
DISPLAY 0.617021 (-4800 4250);
PAINT SKYBLUE (-4800 4250);
FORCEPROP 1 LAST LOCATION C1D16
J 0
(-4800 4300);
DISPLAY 0.617021 (-4800 4300);
PAINT AQUA (-4800 4300);
FORCEPROP 1 LASTPIN (-4850 4100) $PN 2
J 0
(-4840 4080);
DISPLAY 0.617021 (-4840 4080);
PAINT ORANGE (-4840 4080);
FORCEPROP 2 LAST SEC 1
J 0
(-4800 4400);
DISPLAY 0.680851 (-4800 4400);
PAINT MONO (-4800 4400);
DISPLAY INVISIBLE (-4800 4400);
FORCEPROP 2 LAST SEC_TYPE 0402
J 0
(-4800 4400);
DISPLAY 1.021277 (-4800 4400);
PAINT ORANGE (-4800 4400);
DISPLAY INVISIBLE (-4800 4400);
FORCEPROP 2 LAST ROOM PVCCIN_CPU1_PWR_VR
J 0
(-4800 4350);
DISPLAY 1.361702 (-4800 4350);
PAINT ORANGE (-4800 4350);
DISPLAY INVISIBLE (-4800 4350);
FORCEPROP 1 LAST PATH I38
J 0
(-4800 4350);
DISPLAY 0.978723 (-4800 4350);
PAINT WHITE (-4800 4350);
DISPLAY INVISIBLE (-4800 4350);
FORCEPROP 2 LAST CDS_LOCATION C1D16
J 0
(-4800 4300);
DISPLAY 0.617021 (-4800 4300);
PAINT AQUA (-4800 4300);
DISPLAY INVISIBLE (-4800 4300);
FORCEPROP 2 LAST CDS_LIB mstr_discrete
J 0
(-4850 4200);
PAINT ORANGE (-4850 4200);
DISPLAY INVISIBLE (-4850 4200);
FORCEADD CAP_A..1
R 2
(-5000 4200);
FORCEPROP 1 LAST PART_NUMBER D97712-004
J 2
(-5050 4050);
DISPLAY 0.617021 (-5050 4050);
PAINT BLUE (-5050 4050);
FORCEPROP 1 LAST PACK_TYPE 0402V
J 2
(-5050 4000);
DISPLAY 0.617021 (-5050 4000);
PAINT SKYBLUE (-5050 4000);
FORCEPROP 1 LASTPIN (-5000 4300) $PN 1
J 2
(-5010 4280);
DISPLAY 0.617021 (-5010 4280);
PAINT ORANGE (-5010 4280);
FORCEPROP 1 LAST LOCATION C1D15
J 2
(-5050 4300);
DISPLAY 0.617021 (-5050 4300);
PAINT AQUA (-5050 4300);
FORCEPROP 1 LAST VALUE 1.0UF
J 2
(-5050 4250);
DISPLAY 0.617021 (-5050 4250);
PAINT SKYBLUE (-5050 4250);
FORCEPROP 1 LAST TOLERANCE 10%
J 2
(-5050 4150);
DISPLAY 0.617021 (-5050 4150);
PAINT SKYBLUE (-5050 4150);
FORCEPROP 1 LAST VOLTAGE 6.3V
J 2
(-5050 4200);
DISPLAY 0.617021 (-5050 4200);
PAINT SKYBLUE (-5050 4200);
FORCEPROP 1 LAST MATERIAL X6S
J 2
(-5050 4100);
DISPLAY 0.617021 (-5050 4100);
PAINT SKYBLUE (-5050 4100);
FORCEPROP 1 LASTPIN (-5000 4100) $PN 2
J 2
(-5010 4080);
DISPLAY 0.617021 (-5010 4080);
PAINT ORANGE (-5010 4080);
FORCEPROP 2 LAST SEC_TYPE 0402V
J 0
(-5050 4400);
DISPLAY 1.021277 (-5050 4400);
PAINT ORANGE (-5050 4400);
DISPLAY INVISIBLE (-5050 4400);
FORCEPROP 2 LAST SEC 1
J 0
(-5050 4400);
DISPLAY 0.680851 (-5050 4400);
PAINT MONO (-5050 4400);
DISPLAY INVISIBLE (-5050 4400);
FORCEPROP 2 LAST ROOM PVCCIN_CPU1_PWR_VR
J 0
(-5050 4350);
DISPLAY 1.361702 (-5050 4350);
PAINT ORANGE (-5050 4350);
DISPLAY INVISIBLE (-5050 4350);
FORCEPROP 1 LAST PATH I39
J 2
(-5050 4350);
DISPLAY 0.978723 (-5050 4350);
PAINT WHITE (-5050 4350);
DISPLAY INVISIBLE (-5050 4350);
FORCEPROP 2 LAST CDS_SEC 1
J 0
(-5050 4350);
PAINT ORANGE (-5050 4350);
DISPLAY INVISIBLE (-5050 4350);
FORCEPROP 2 LAST CDS_LIB dev_discrete
J 0
(-5000 4200);
PAINT ORANGE (-5000 4200);
DISPLAY INVISIBLE (-5000 4200);
FORCEPROP 2 LAST CDS_LOCATION C1D15
J 2
(-5050 4300);
DISPLAY 0.617021 (-5050 4300);
PAINT AQUA (-5050 4300);
DISPLAY INVISIBLE (-5050 4300);
FORCEADD CAP..1
R 2
(-5975 3575);
FORCEPROP 1 LAST TOLERANCE 10%
J 2
(-6025 3525);
DISPLAY 0.617021 (-6025 3525);
PAINT SKYBLUE (-6025 3525);
FORCEPROP 1 LAST VOLTAGE 16V
J 2
(-6025 3575);
DISPLAY 0.617021 (-6025 3575);
PAINT SKYBLUE (-6025 3575);
FORCEPROP 1 LAST LOCATION C1D20
J 2
(-6025 3675);
DISPLAY 0.617021 (-6025 3675);
PAINT AQUA (-6025 3675);
FORCEPROP 1 LAST VALUE 0.220UF
J 2
(-6025 3625);
DISPLAY 0.617021 (-6025 3625);
PAINT SKYBLUE (-6025 3625);
FORCEPROP 1 LASTPIN (-5975 3675) $PN 1
J 2
(-5985 3655);
DISPLAY 0.617021 (-5985 3655);
PAINT ORANGE (-5985 3655);
FORCEPROP 1 LASTPIN (-5975 3475) $PN 2
J 2
(-5985 3455);
DISPLAY 0.617021 (-5985 3455);
PAINT ORANGE (-5985 3455);
FORCEPROP 1 LAST PART_NUMBER A36096-104
J 2
(-6025 3425);
DISPLAY 0.617021 (-6025 3425);
PAINT BLUE (-6025 3425);
FORCEPROP 1 LAST PACK_TYPE 0402
J 2
(-6025 3375);
DISPLAY 0.617021 (-6025 3375);
PAINT SKYBLUE (-6025 3375);
FORCEPROP 1 LAST MATERIAL X7R
J 2
(-6025 3475);
DISPLAY 0.617021 (-6025 3475);
PAINT SKYBLUE (-6025 3475);
FORCEPROP 2 LAST CDS_LIB mstr_discrete
J 0
(-5975 3575);
PAINT ORANGE (-5975 3575);
DISPLAY INVISIBLE (-5975 3575);
FORCEPROP 2 LAST SEC_TYPE 0402
J 0
(-6025 3775);
DISPLAY 1.021277 (-6025 3775);
PAINT ORANGE (-6025 3775);
DISPLAY INVISIBLE (-6025 3775);
FORCEPROP 0 LAST SPOF TRUE
J 0
(-6025 3775);
DISPLAY 1.021277 (-6025 3775);
PAINT ORANGE (-6025 3775);
DISPLAY INVISIBLE (-6025 3775);
FORCEPROP 2 LAST SEC 1
J 0
(-6025 3775);
DISPLAY 0.680851 (-6025 3775);
PAINT MONO (-6025 3775);
DISPLAY INVISIBLE (-6025 3775);
FORCEPROP 2 LAST CDS_LOCATION C1D20
J 2
(-6025 3675);
DISPLAY 0.617021 (-6025 3675);
PAINT AQUA (-6025 3675);
DISPLAY INVISIBLE (-6025 3675);
FORCEPROP 2 LAST NO_XNET_CONNECTION 1
J 0
(-6025 3775);
PAINT MONO (-6025 3775);
DISPLAY INVISIBLE (-6025 3775);
FORCEPROP 1 LAST PATH I40
J 2
(-6025 3725);
DISPLAY 0.978723 (-6025 3725);
PAINT WHITE (-6025 3725);
DISPLAY INVISIBLE (-6025 3725);
FORCEPROP 2 LAST ROOM PVCCIN_CPU1_PWR_VR
J 0
(-6050 3725);
DISPLAY 1.361702 (-6050 3725);
PAINT ORANGE (-6050 3725);
DISPLAY INVISIBLE (-6050 3725);
FORCEADD CAP..1
(-5575 4150);
FORCEPROP 1 LAST PART_NUMBER D97712-011
J 0
(-5525 4000);
DISPLAY 0.617021 (-5525 4000);
PAINT BLUE (-5525 4000);
FORCEPROP 1 LASTPIN (-5575 4050) $PN 2
J 0
(-5565 4030);
DISPLAY 0.617021 (-5565 4030);
PAINT ORANGE (-5565 4030);
FORCEPROP 1 LAST VALUE 1.0UF
J 0
(-5525 4200);
DISPLAY 0.617021 (-5525 4200);
PAINT SKYBLUE (-5525 4200);
FORCEPROP 1 LAST VOLTAGE 16V
J 0
(-5525 4150);
DISPLAY 0.617021 (-5525 4150);
PAINT SKYBLUE (-5525 4150);
FORCEPROP 1 LAST TOLERANCE 10%
J 0
(-5525 4100);
DISPLAY 0.617021 (-5525 4100);
PAINT SKYBLUE (-5525 4100);
FORCEPROP 1 LASTPIN (-5575 4250) $PN 1
J 0
(-5565 4230);
DISPLAY 0.617021 (-5565 4230);
PAINT ORANGE (-5565 4230);
FORCEPROP 1 LAST LOCATION C1D17
J 0
(-5525 4250);
DISPLAY 0.617021 (-5525 4250);
PAINT AQUA (-5525 4250);
FORCEPROP 1 LAST MATERIAL X6S
J 0
(-5525 4050);
DISPLAY 0.617021 (-5525 4050);
PAINT SKYBLUE (-5525 4050);
FORCEPROP 1 LAST PACK_TYPE 0402
J 0
(-5525 3950);
DISPLAY 0.617021 (-5525 3950);
PAINT SKYBLUE (-5525 3950);
FORCEPROP 2 LAST SEC_TYPE 0402
J 0
(-5525 4350);
DISPLAY 1.021277 (-5525 4350);
PAINT ORANGE (-5525 4350);
DISPLAY INVISIBLE (-5525 4350);
FORCEPROP 2 LAST SEC 1
J 0
(-5525 4350);
DISPLAY 0.680851 (-5525 4350);
PAINT MONO (-5525 4350);
DISPLAY INVISIBLE (-5525 4350);
FORCEPROP 2 LAST ROOM PVCCIN_CPU1_PWR_VR
J 0
(-5525 4300);
DISPLAY 1.361702 (-5525 4300);
PAINT ORANGE (-5525 4300);
DISPLAY INVISIBLE (-5525 4300);
FORCEPROP 2 LAST CDS_LIB mstr_discrete
J 0
(-5575 4150);
PAINT ORANGE (-5575 4150);
DISPLAY INVISIBLE (-5575 4150);
FORCEPROP 2 LAST CDS_LOCATION C1D17
J 0
(-5525 4250);
DISPLAY 0.617021 (-5525 4250);
PAINT AQUA (-5525 4250);
DISPLAY INVISIBLE (-5525 4250);
FORCEPROP 1 LAST PATH I43
J 0
(-5525 4300);
DISPLAY 0.978723 (-5525 4300);
PAINT WHITE (-5525 4300);
DISPLAY INVISIBLE (-5525 4300);
FORCEADD CAP_A..1
(-5875 4150);
FORCEPROP 1 LAST VOLTAGE 16V
J 0
(-5825 4150);
DISPLAY 0.617021 (-5825 4150);
PAINT SKYBLUE (-5825 4150);
FORCEPROP 1 LAST VALUE 0.1UF
J 0
(-5825 4200);
DISPLAY 0.617021 (-5825 4200);
PAINT SKYBLUE (-5825 4200);
FORCEPROP 1 LAST LOCATION C1D28
J 0
(-5825 4250);
DISPLAY 0.617021 (-5825 4250);
PAINT AQUA (-5825 4250);
FORCEPROP 1 LAST TOLERANCE 10%
J 0
(-5825 4100);
DISPLAY 0.617021 (-5825 4100);
PAINT SKYBLUE (-5825 4100);
FORCEPROP 1 LASTPIN (-5875 4250) $PN 1
J 0
(-5865 4230);
DISPLAY 0.617021 (-5865 4230);
PAINT ORANGE (-5865 4230);
FORCEPROP 1 LAST MATERIAL X7R
J 0
(-5825 4050);
DISPLAY 0.617021 (-5825 4050);
PAINT SKYBLUE (-5825 4050);
FORCEPROP 1 LAST PACK_TYPE 0402V
J 0
(-5825 3950);
DISPLAY 0.617021 (-5825 3950);
PAINT SKYBLUE (-5825 3950);
FORCEPROP 1 LASTPIN (-5875 4050) $PN 2
J 0
(-5865 4030);
DISPLAY 0.617021 (-5865 4030);
PAINT ORANGE (-5865 4030);
FORCEPROP 1 LAST PART_NUMBER A36096-030
J 0
(-5825 4000);
DISPLAY 0.617021 (-5825 4000);
PAINT BLUE (-5825 4000);
FORCEPROP 2 LAST SEC 1
J 0
(-5825 4350);
DISPLAY 0.680851 (-5825 4350);
PAINT MONO (-5825 4350);
DISPLAY INVISIBLE (-5825 4350);
FORCEPROP 2 LAST SEC_TYPE 0402V
J 0
(-5825 4350);
DISPLAY 1.021277 (-5825 4350);
PAINT ORANGE (-5825 4350);
DISPLAY INVISIBLE (-5825 4350);
FORCEPROP 2 LAST ROOM PVCCIN_CPU1_PWR_VR
J 0
(-5825 4300);
DISPLAY 1.361702 (-5825 4300);
PAINT ORANGE (-5825 4300);
DISPLAY INVISIBLE (-5825 4300);
FORCEPROP 2 LAST CDS_SEC 1
J 0
(-5825 4300);
PAINT ORANGE (-5825 4300);
DISPLAY INVISIBLE (-5825 4300);
FORCEPROP 2 LAST CDS_LIB dev_discrete
J 0
(-5875 4150);
PAINT ORANGE (-5875 4150);
DISPLAY INVISIBLE (-5875 4150);
FORCEPROP 2 LAST CDS_LOCATION C1D28
J 0
(-5825 4250);
DISPLAY 0.617021 (-5825 4250);
PAINT AQUA (-5825 4250);
DISPLAY INVISIBLE (-5825 4250);
FORCEPROP 1 LAST PATH I44
J 0
(-5825 4300);
DISPLAY 0.978723 (-5825 4300);
PAINT WHITE (-5825 4300);
DISPLAY INVISIBLE (-5825 4300);
FORCEADD CAP..1
(-6250 4150);
FORCEPROP 1 LAST PART_NUMBER D97712-011
J 0
(-6200 4000);
DISPLAY 0.617021 (-6200 4000);
PAINT BLUE (-6200 4000);
FORCEPROP 1 LAST LOCATION C1D23
J 0
(-6200 4250);
DISPLAY 0.617021 (-6200 4250);
PAINT AQUA (-6200 4250);
FORCEPROP 1 LAST VALUE 1.0UF
J 0
(-6200 4200);
DISPLAY 0.617021 (-6200 4200);
PAINT SKYBLUE (-6200 4200);
FORCEPROP 1 LAST TOLERANCE 10%
J 0
(-6200 4100);
DISPLAY 0.617021 (-6200 4100);
PAINT SKYBLUE (-6200 4100);
FORCEPROP 1 LAST VOLTAGE 16V
J 0
(-6200 4150);
DISPLAY 0.617021 (-6200 4150);
PAINT SKYBLUE (-6200 4150);
FORCEPROP 1 LASTPIN (-6250 4250) $PN 1
J 0
(-6240 4230);
DISPLAY 0.617021 (-6240 4230);
PAINT ORANGE (-6240 4230);
FORCEPROP 1 LAST PACK_TYPE 0402
J 0
(-6200 3950);
DISPLAY 0.617021 (-6200 3950);
PAINT SKYBLUE (-6200 3950);
FORCEPROP 1 LAST MATERIAL X6S
J 0
(-6200 4050);
DISPLAY 0.617021 (-6200 4050);
PAINT SKYBLUE (-6200 4050);
FORCEPROP 1 LASTPIN (-6250 4050) $PN 2
J 0
(-6240 4030);
DISPLAY 0.617021 (-6240 4030);
PAINT ORANGE (-6240 4030);
FORCEPROP 2 LAST ROOM PVCCIN_CPU1_PWR_VR
J 0
(-6200 4300);
DISPLAY 1.361702 (-6200 4300);
PAINT ORANGE (-6200 4300);
DISPLAY INVISIBLE (-6200 4300);
FORCEPROP 2 LAST SEC 1
J 0
(-6200 4350);
DISPLAY 0.680851 (-6200 4350);
PAINT MONO (-6200 4350);
DISPLAY INVISIBLE (-6200 4350);
FORCEPROP 2 LAST SEC_TYPE 0402
J 0
(-6200 4350);
DISPLAY 1.021277 (-6200 4350);
PAINT ORANGE (-6200 4350);
DISPLAY INVISIBLE (-6200 4350);
FORCEPROP 1 LAST PATH I45
J 0
(-6200 4300);
DISPLAY 0.978723 (-6200 4300);
PAINT WHITE (-6200 4300);
DISPLAY INVISIBLE (-6200 4300);
FORCEPROP 2 LAST CDS_LOCATION C1D23
J 0
(-6200 4250);
DISPLAY 0.617021 (-6200 4250);
PAINT AQUA (-6200 4250);
DISPLAY INVISIBLE (-6200 4250);
FORCEPROP 2 LAST CDS_LIB mstr_discrete
J 0
(-6250 4150);
PAINT ORANGE (-6250 4150);
DISPLAY INVISIBLE (-6250 4150);
FORCEADD CAP..1
(-4900 1575);
FORCEPROP 1 LAST MATERIAL X7R
J 0
(-4850 1475);
DISPLAY 0.617021 (-4850 1475);
PAINT SKYBLUE (-4850 1475);
FORCEPROP 1 LAST PACK_TYPE 0402
J 0
(-4850 1375);
DISPLAY 0.617021 (-4850 1375);
PAINT SKYBLUE (-4850 1375);
FORCEPROP 1 LAST LOCATION C1D6
J 0
(-4850 1675);
DISPLAY 0.617021 (-4850 1675);
PAINT AQUA (-4850 1675);
FORCEPROP 1 LAST VALUE 0.22UF
J 0
(-4850 1625);
DISPLAY 0.617021 (-4850 1625);
PAINT SKYBLUE (-4850 1625);
FORCEPROP 1 LAST VOLTAGE 16V
J 0
(-4850 1575);
DISPLAY 0.617021 (-4850 1575);
PAINT SKYBLUE (-4850 1575);
FORCEPROP 1 LASTPIN (-4900 1675) $PN 1
J 0
(-4890 1655);
DISPLAY 0.617021 (-4890 1655);
PAINT ORANGE (-4890 1655);
FORCEPROP 1 LAST TOLERANCE 10%
J 0
(-4850 1525);
DISPLAY 0.617021 (-4850 1525);
PAINT SKYBLUE (-4850 1525);
FORCEPROP 1 LASTPIN (-4900 1475) $PN 2
J 0
(-4890 1455);
DISPLAY 0.617021 (-4890 1455);
PAINT ORANGE (-4890 1455);
FORCEPROP 1 LAST PART_NUMBER A36096-155
J 0
(-4850 1425);
DISPLAY 0.617021 (-4850 1425);
PAINT BLUE (-4850 1425);
FORCEPROP 2 LAST SEC_TYPE 0402
J 0
(-4850 1775);
DISPLAY 1.021277 (-4850 1775);
PAINT ORANGE (-4850 1775);
DISPLAY INVISIBLE (-4850 1775);
FORCEPROP 2 LAST SEC 1
J 0
(-4850 1775);
DISPLAY 0.680851 (-4850 1775);
PAINT MONO (-4850 1775);
DISPLAY INVISIBLE (-4850 1775);
FORCEPROP 2 LAST CDS_LOCATION C1D6
J 0
(-4850 1675);
DISPLAY 0.617021 (-4850 1675);
PAINT AQUA (-4850 1675);
DISPLAY INVISIBLE (-4850 1675);
FORCEPROP 1 LAST PATH I46
J 0
(-4850 1725);
DISPLAY 0.978723 (-4850 1725);
PAINT WHITE (-4850 1725);
DISPLAY INVISIBLE (-4850 1725);
FORCEPROP 2 LAST ROOM PVCCIN_CPU1_PWR_VR
J 0
(-4850 1725);
DISPLAY 1.361702 (-4850 1725);
PAINT ORANGE (-4850 1725);
DISPLAY INVISIBLE (-4850 1725);
FORCEPROP 2 LAST CDS_LIB mstr_discrete
J 0
(-4900 1575);
PAINT ORANGE (-4900 1575);
DISPLAY INVISIBLE (-4900 1575);
FORCEADD CAP_A..1
R 2
(-5075 1575);
FORCEPROP 1 LAST PART_NUMBER D97712-004
J 2
(-5125 1425);
DISPLAY 0.617021 (-5125 1425);
PAINT BLUE (-5125 1425);
FORCEPROP 1 LAST VALUE 1.0UF
J 2
(-5125 1625);
DISPLAY 0.617021 (-5125 1625);
PAINT SKYBLUE (-5125 1625);
FORCEPROP 1 LASTPIN (-5075 1675) $PN 1
J 2
(-5085 1655);
DISPLAY 0.617021 (-5085 1655);
PAINT ORANGE (-5085 1655);
FORCEPROP 1 LASTPIN (-5075 1475) $PN 2
J 2
(-5085 1455);
DISPLAY 0.617021 (-5085 1455);
PAINT ORANGE (-5085 1455);
FORCEPROP 1 LAST LOCATION C1D5
J 2
(-5125 1675);
DISPLAY 0.617021 (-5125 1675);
PAINT AQUA (-5125 1675);
FORCEPROP 1 LAST VOLTAGE 6.3V
J 2
(-5125 1575);
DISPLAY 0.617021 (-5125 1575);
PAINT SKYBLUE (-5125 1575);
FORCEPROP 1 LAST TOLERANCE 10%
J 2
(-5125 1525);
DISPLAY 0.617021 (-5125 1525);
PAINT SKYBLUE (-5125 1525);
FORCEPROP 1 LAST PACK_TYPE 0402V
J 2
(-5125 1375);
DISPLAY 0.617021 (-5125 1375);
PAINT SKYBLUE (-5125 1375);
FORCEPROP 1 LAST MATERIAL X6S
J 2
(-5125 1475);
DISPLAY 0.617021 (-5125 1475);
PAINT SKYBLUE (-5125 1475);
FORCEPROP 2 LAST CDS_LIB dev_discrete
J 0
(-5075 1575);
PAINT ORANGE (-5075 1575);
DISPLAY INVISIBLE (-5075 1575);
FORCEPROP 2 LAST CDS_LOCATION C1D5
J 2
(-5125 1675);
DISPLAY 0.617021 (-5125 1675);
PAINT AQUA (-5125 1675);
DISPLAY INVISIBLE (-5125 1675);
FORCEPROP 2 LAST CDS_SEC 1
J 0
(-5125 1725);
PAINT ORANGE (-5125 1725);
DISPLAY INVISIBLE (-5125 1725);
FORCEPROP 2 LAST SEC_TYPE 0402V
J 0
(-5125 1775);
DISPLAY 1.021277 (-5125 1775);
PAINT ORANGE (-5125 1775);
DISPLAY INVISIBLE (-5125 1775);
FORCEPROP 2 LAST SEC 1
J 0
(-5125 1775);
DISPLAY 0.680851 (-5125 1775);
PAINT MONO (-5125 1775);
DISPLAY INVISIBLE (-5125 1775);
FORCEPROP 1 LAST PATH I47
J 2
(-5125 1725);
DISPLAY 0.978723 (-5125 1725);
PAINT WHITE (-5125 1725);
DISPLAY INVISIBLE (-5125 1725);
FORCEPROP 2 LAST ROOM PVCCIN_CPU1_PWR_VR
J 0
(-5125 1725);
DISPLAY 1.361702 (-5125 1725);
PAINT ORANGE (-5125 1725);
DISPLAY INVISIBLE (-5125 1725);
FORCEADD CAP..1
R 2
(-5975 900);
FORCEPROP 1 LAST TOLERANCE 10%
J 2
(-6025 850);
DISPLAY 0.617021 (-6025 850);
PAINT SKYBLUE (-6025 850);
FORCEPROP 1 LAST MATERIAL X7R
J 2
(-6025 800);
DISPLAY 0.617021 (-6025 800);
PAINT SKYBLUE (-6025 800);
FORCEPROP 1 LASTPIN (-5975 1000) $PN 1
J 2
(-5985 980);
DISPLAY 0.617021 (-5985 980);
PAINT ORANGE (-5985 980);
FORCEPROP 1 LAST LOCATION C1D10
J 2
(-6025 1000);
DISPLAY 0.617021 (-6025 1000);
PAINT AQUA (-6025 1000);
FORCEPROP 1 LASTPIN (-5975 800) $PN 2
J 2
(-5985 780);
DISPLAY 0.617021 (-5985 780);
PAINT ORANGE (-5985 780);
FORCEPROP 1 LAST PACK_TYPE 0402
J 2
(-6025 700);
DISPLAY 0.617021 (-6025 700);
PAINT SKYBLUE (-6025 700);
FORCEPROP 1 LAST VALUE 0.220UF
J 2
(-6025 950);
DISPLAY 0.617021 (-6025 950);
PAINT SKYBLUE (-6025 950);
FORCEPROP 1 LAST PART_NUMBER A36096-104
J 2
(-6025 750);
DISPLAY 0.617021 (-6025 750);
PAINT BLUE (-6025 750);
FORCEPROP 1 LAST VOLTAGE 16V
J 2
(-6025 900);
DISPLAY 0.617021 (-6025 900);
PAINT SKYBLUE (-6025 900);
FORCEPROP 0 LAST SPOF TRUE
J 0
(-6025 1100);
DISPLAY 1.021277 (-6025 1100);
PAINT ORANGE (-6025 1100);
DISPLAY INVISIBLE (-6025 1100);
FORCEPROP 2 LAST SEC_TYPE 0402
J 0
(-6025 1100);
DISPLAY 1.021277 (-6025 1100);
PAINT ORANGE (-6025 1100);
DISPLAY INVISIBLE (-6025 1100);
FORCEPROP 2 LAST SEC 1
J 0
(-6025 1100);
DISPLAY 0.680851 (-6025 1100);
PAINT MONO (-6025 1100);
DISPLAY INVISIBLE (-6025 1100);
FORCEPROP 2 LAST CDS_LOCATION C1D10
J 2
(-6025 1000);
DISPLAY 0.617021 (-6025 1000);
PAINT AQUA (-6025 1000);
DISPLAY INVISIBLE (-6025 1000);
FORCEPROP 2 LAST NO_XNET_CONNECTION 1
J 0
(-6025 1100);
PAINT MONO (-6025 1100);
DISPLAY INVISIBLE (-6025 1100);
FORCEPROP 1 LAST PATH I48
J 2
(-6025 1050);
DISPLAY 0.978723 (-6025 1050);
PAINT WHITE (-6025 1050);
DISPLAY INVISIBLE (-6025 1050);
FORCEPROP 2 LAST ROOM PVCCIN_CPU1_PWR_VR
J 0
(-6025 1050);
DISPLAY 1.361702 (-6025 1050);
PAINT ORANGE (-6025 1050);
DISPLAY INVISIBLE (-6025 1050);
FORCEPROP 2 LAST CDS_LIB mstr_discrete
J 0
(-5975 900);
PAINT ORANGE (-5975 900);
DISPLAY INVISIBLE (-5975 900);
FORCEADD RES..1
(-5450 2025);
FORCEPROP 1 LAST MATERIAL CHIP
J 0
(-5375 1850);
DISPLAY 0.617021 (-5375 1850);
PAINT SKYBLUE (-5375 1850);
FORCEPROP 1 LAST PACK_TYPE 0402
J 0
(-5400 1900);
DISPLAY 0.617021 (-5400 1900);
PAINT SKYBLUE (-5400 1900);
FORCEPROP 1 LAST PART_NUMBER G21796-090
J 0
(-5575 1950);
DISPLAY 0.617021 (-5575 1950);
PAINT BLUE (-5575 1950);
FORCEPROP 1 LAST LOCATION R9P8
J 0
(-5500 2075);
DISPLAY 0.617021 (-5500 2075);
PAINT AQUA (-5500 2075);
FORCEPROP 1 LAST VALUE 1.0
J 2
(-5550 1900);
DISPLAY 0.617021 (-5550 1900);
PAINT SKYBLUE (-5550 1900);
FORCEPROP 1 LAST WATTAGE 1/16W
J 2
(-5425 1850);
DISPLAY 0.617021 (-5425 1850);
PAINT SKYBLUE (-5425 1850);
FORCEPROP 1 LAST TOLERANCE 1%
J 0
(-5500 1900);
DISPLAY 0.617021 (-5500 1900);
PAINT SKYBLUE (-5500 1900);
FORCEPROP 1 LASTPIN (-5550 2025) $PN 1
J 0
(-5538 2037);
DISPLAY 0.617021 (-5538 2037);
PAINT ORANGE (-5538 2037);
FORCEPROP 1 LASTPIN (-5350 2025) $PN 2
J 0
(-5388 2037);
DISPLAY 0.617021 (-5388 2037);
PAINT ORANGE (-5388 2037);
FORCEPROP 2 LAST CDS_LIB mstr_discrete
J 0
(-5450 2025);
PAINT ORANGE (-5450 2025);
DISPLAY INVISIBLE (-5450 2025);
FORCEPROP 2 LAST SEC_TYPE 0402
J 0
(-5500 2225);
DISPLAY 1.021277 (-5500 2225);
PAINT ORANGE (-5500 2225);
DISPLAY INVISIBLE (-5500 2225);
FORCEPROP 2 LAST SEC 1
J 0
(-5500 2225);
DISPLAY 0.680851 (-5500 2225);
PAINT MONO (-5500 2225);
DISPLAY INVISIBLE (-5500 2225);
FORCEPROP 2 LAST CDS_LOCATION R9P8
J 0
(-5500 2075);
DISPLAY 0.617021 (-5500 2075);
PAINT AQUA (-5500 2075);
DISPLAY INVISIBLE (-5500 2075);
FORCEPROP 1 LAST PATH I49
J 0
(-5500 2175);
DISPLAY 0.978723 (-5500 2175);
PAINT WHITE (-5500 2175);
DISPLAY INVISIBLE (-5500 2175);
FORCEPROP 2 LAST ROOM PVCCIN_CPU1_PWR_VR
J 0
(-5500 2125);
DISPLAY 1.361702 (-5500 2125);
PAINT ORANGE (-5500 2125);
DISPLAY INVISIBLE (-5500 2125);
FORCEADD CAP..1
(-5700 1575);
FORCEPROP 1 LAST TOLERANCE 10%
J 0
(-5650 1525);
DISPLAY 0.617021 (-5650 1525);
PAINT SKYBLUE (-5650 1525);
FORCEPROP 1 LAST VOLTAGE 16V
J 0
(-5650 1575);
DISPLAY 0.617021 (-5650 1575);
PAINT SKYBLUE (-5650 1575);
FORCEPROP 1 LAST LOCATION C1D7
J 0
(-5650 1675);
DISPLAY 0.617021 (-5650 1675);
PAINT AQUA (-5650 1675);
FORCEPROP 1 LAST PART_NUMBER D97712-011
J 0
(-5650 1425);
DISPLAY 0.617021 (-5650 1425);
PAINT BLUE (-5650 1425);
FORCEPROP 1 LAST VALUE 1.0UF
J 0
(-5650 1625);
DISPLAY 0.617021 (-5650 1625);
PAINT SKYBLUE (-5650 1625);
FORCEPROP 1 LAST PACK_TYPE 0402
J 0
(-5650 1375);
DISPLAY 0.617021 (-5650 1375);
PAINT SKYBLUE (-5650 1375);
FORCEPROP 1 LAST MATERIAL X6S
J 0
(-5650 1475);
DISPLAY 0.617021 (-5650 1475);
PAINT SKYBLUE (-5650 1475);
FORCEPROP 1 LASTPIN (-5700 1675) $PN 1
J 0
(-5690 1655);
DISPLAY 0.617021 (-5690 1655);
PAINT ORANGE (-5690 1655);
FORCEPROP 1 LASTPIN (-5700 1475) $PN 2
J 0
(-5690 1455);
DISPLAY 0.617021 (-5690 1455);
PAINT ORANGE (-5690 1455);
FORCEPROP 2 LAST SEC 1
J 0
(-5650 1775);
DISPLAY 0.680851 (-5650 1775);
PAINT MONO (-5650 1775);
DISPLAY INVISIBLE (-5650 1775);
FORCEPROP 2 LAST SEC_TYPE 0402
J 0
(-5650 1775);
DISPLAY 1.021277 (-5650 1775);
PAINT ORANGE (-5650 1775);
DISPLAY INVISIBLE (-5650 1775);
FORCEPROP 2 LAST ROOM PVCCIN_CPU1_PWR_VR
J 0
(-5650 1725);
DISPLAY 1.361702 (-5650 1725);
PAINT ORANGE (-5650 1725);
DISPLAY INVISIBLE (-5650 1725);
FORCEPROP 1 LAST PATH I50
J 0
(-5650 1725);
DISPLAY 0.978723 (-5650 1725);
PAINT WHITE (-5650 1725);
DISPLAY INVISIBLE (-5650 1725);
FORCEPROP 2 LAST CDS_LOCATION C1D7
J 0
(-5650 1675);
DISPLAY 0.617021 (-5650 1675);
PAINT AQUA (-5650 1675);
DISPLAY INVISIBLE (-5650 1675);
FORCEPROP 2 LAST CDS_LIB mstr_discrete
J 0
(-5700 1575);
PAINT ORANGE (-5700 1575);
DISPLAY INVISIBLE (-5700 1575);
FORCEADD CAP_A..1
(-6025 1450);
FORCEPROP 1 LAST LOCATION C1D13
J 0
(-5975 1550);
DISPLAY 0.617021 (-5975 1550);
PAINT AQUA (-5975 1550);
FORCEPROP 1 LASTPIN (-6025 1550) $PN 1
J 0
(-6015 1530);
DISPLAY 0.617021 (-6015 1530);
PAINT ORANGE (-6015 1530);
FORCEPROP 1 LAST MATERIAL X7R
J 0
(-5975 1350);
DISPLAY 0.617021 (-5975 1350);
PAINT SKYBLUE (-5975 1350);
FORCEPROP 1 LAST VOLTAGE 16V
J 0
(-5975 1450);
DISPLAY 0.617021 (-5975 1450);
PAINT SKYBLUE (-5975 1450);
FORCEPROP 1 LAST PACK_TYPE 0402V
J 0
(-5975 1250);
DISPLAY 0.617021 (-5975 1250);
PAINT SKYBLUE (-5975 1250);
FORCEPROP 1 LAST TOLERANCE 10%
J 0
(-5975 1400);
DISPLAY 0.617021 (-5975 1400);
PAINT SKYBLUE (-5975 1400);
FORCEPROP 1 LAST VALUE 0.1UF
J 0
(-5975 1500);
DISPLAY 0.617021 (-5975 1500);
PAINT SKYBLUE (-5975 1500);
FORCEPROP 1 LAST PART_NUMBER A36096-030
J 0
(-5975 1300);
DISPLAY 0.617021 (-5975 1300);
PAINT BLUE (-5975 1300);
FORCEPROP 1 LASTPIN (-6025 1350) $PN 2
J 0
(-6015 1330);
DISPLAY 0.617021 (-6015 1330);
PAINT ORANGE (-6015 1330);
FORCEPROP 2 LAST SEC 1
J 0
(-5975 1650);
DISPLAY 0.680851 (-5975 1650);
PAINT MONO (-5975 1650);
DISPLAY INVISIBLE (-5975 1650);
FORCEPROP 2 LAST SEC_TYPE 0402V
J 0
(-5975 1650);
DISPLAY 1.021277 (-5975 1650);
PAINT ORANGE (-5975 1650);
DISPLAY INVISIBLE (-5975 1650);
FORCEPROP 2 LAST CDS_SEC 1
J 0
(-5975 1600);
PAINT ORANGE (-5975 1600);
DISPLAY INVISIBLE (-5975 1600);
FORCEPROP 2 LAST CDS_LOCATION C1D13
J 0
(-5975 1550);
DISPLAY 0.617021 (-5975 1550);
PAINT AQUA (-5975 1550);
DISPLAY INVISIBLE (-5975 1550);
FORCEPROP 2 LAST ROOM PVCCIN_CPU1_PWR_VR
J 0
(-5975 1600);
DISPLAY 1.361702 (-5975 1600);
PAINT ORANGE (-5975 1600);
DISPLAY INVISIBLE (-5975 1600);
FORCEPROP 1 LAST PATH I51
J 0
(-5975 1600);
DISPLAY 0.978723 (-5975 1600);
PAINT WHITE (-5975 1600);
DISPLAY INVISIBLE (-5975 1600);
FORCEPROP 2 LAST CDS_LIB dev_discrete
J 0
(-6025 1450);
PAINT ORANGE (-6025 1450);
DISPLAY INVISIBLE (-6025 1450);
FORCEADD CAP..1
(-6350 1500);
FORCEPROP 1 LAST PART_NUMBER D97712-011
J 0
(-6300 1350);
DISPLAY 0.617021 (-6300 1350);
PAINT BLUE (-6300 1350);
FORCEPROP 1 LAST LOCATION C1D12
J 0
(-6300 1600);
DISPLAY 0.617021 (-6300 1600);
PAINT AQUA (-6300 1600);
FORCEPROP 1 LAST VALUE 1.0UF
J 0
(-6300 1550);
DISPLAY 0.617021 (-6300 1550);
PAINT SKYBLUE (-6300 1550);
FORCEPROP 1 LASTPIN (-6350 1600) $PN 1
J 0
(-6340 1580);
DISPLAY 0.617021 (-6340 1580);
PAINT ORANGE (-6340 1580);
FORCEPROP 1 LAST TOLERANCE 10%
J 0
(-6300 1450);
DISPLAY 0.617021 (-6300 1450);
PAINT SKYBLUE (-6300 1450);
FORCEPROP 1 LAST PACK_TYPE 0402
J 0
(-6300 1300);
DISPLAY 0.617021 (-6300 1300);
PAINT SKYBLUE (-6300 1300);
FORCEPROP 1 LAST VOLTAGE 16V
J 0
(-6300 1500);
DISPLAY 0.617021 (-6300 1500);
PAINT SKYBLUE (-6300 1500);
FORCEPROP 1 LAST MATERIAL X6S
J 0
(-6300 1400);
DISPLAY 0.617021 (-6300 1400);
PAINT SKYBLUE (-6300 1400);
FORCEPROP 1 LASTPIN (-6350 1400) $PN 2
J 0
(-6340 1380);
DISPLAY 0.617021 (-6340 1380);
PAINT ORANGE (-6340 1380);
FORCEPROP 2 LAST SEC_TYPE 0402
J 0
(-6300 1700);
DISPLAY 1.021277 (-6300 1700);
PAINT ORANGE (-6300 1700);
DISPLAY INVISIBLE (-6300 1700);
FORCEPROP 2 LAST SEC 1
J 0
(-6300 1700);
DISPLAY 0.680851 (-6300 1700);
PAINT MONO (-6300 1700);
DISPLAY INVISIBLE (-6300 1700);
FORCEPROP 2 LAST CDS_LOCATION C1D12
J 0
(-6300 1600);
DISPLAY 0.617021 (-6300 1600);
PAINT AQUA (-6300 1600);
DISPLAY INVISIBLE (-6300 1600);
FORCEPROP 1 LAST PATH I52
J 0
(-6300 1650);
DISPLAY 0.978723 (-6300 1650);
PAINT WHITE (-6300 1650);
DISPLAY INVISIBLE (-6300 1650);
FORCEPROP 2 LAST ROOM PVCCIN_CPU1_PWR_VR
J 0
(-6300 1650);
DISPLAY 1.361702 (-6300 1650);
PAINT ORANGE (-6300 1650);
DISPLAY INVISIBLE (-6300 1650);
FORCEPROP 2 LAST CDS_LIB mstr_discrete
J 0
(-6350 1500);
PAINT ORANGE (-6350 1500);
DISPLAY INVISIBLE (-6350 1500);
FORCEADD CAP..1
(-6625 4150);
FORCEPROP 1 LASTPIN (-6625 4250) $PN 1
J 0
(-6615 4230);
DISPLAY 0.617021 (-6615 4230);
PAINT ORANGE (-6615 4230);
FORCEPROP 1 LAST VOLTAGE 16V
J 0
(-6575 4150);
DISPLAY 0.617021 (-6575 4150);
PAINT SKYBLUE (-6575 4150);
FORCEPROP 1 LAST TOLERANCE 10%
J 0
(-6575 4100);
DISPLAY 0.617021 (-6575 4100);
PAINT SKYBLUE (-6575 4100);
FORCEPROP 1 LAST VALUE 10UF
J 0
(-6575 4200);
DISPLAY 0.617021 (-6575 4200);
PAINT SKYBLUE (-6575 4200);
FORCEPROP 1 LAST LOCATION C9P4
J 0
(-6575 4250);
DISPLAY 0.617021 (-6575 4250);
PAINT AQUA (-6575 4250);
FORCEPROP 1 LAST PART_NUMBER C95333-007
J 0
(-6575 4000);
DISPLAY 0.617021 (-6575 4000);
PAINT BLUE (-6575 4000);
FORCEPROP 1 LAST PACK_TYPE 0805
J 0
(-6575 3950);
DISPLAY 0.617021 (-6575 3950);
PAINT SKYBLUE (-6575 3950);
FORCEPROP 1 LAST MATERIAL X6S
J 0
(-6575 4050);
DISPLAY 0.617021 (-6575 4050);
PAINT SKYBLUE (-6575 4050);
FORCEPROP 1 LASTPIN (-6625 4050) $PN 2
J 0
(-6615 4030);
DISPLAY 0.617021 (-6615 4030);
PAINT ORANGE (-6615 4030);
FORCEPROP 2 LAST ROOM PVCCIN_CPU1_PWR_VR
J 0
(-6575 4300);
DISPLAY 1.361702 (-6575 4300);
PAINT ORANGE (-6575 4300);
DISPLAY INVISIBLE (-6575 4300);
FORCEPROP 2 LAST SEC 1
J 0
(-6575 4350);
DISPLAY 0.680851 (-6575 4350);
PAINT MONO (-6575 4350);
DISPLAY INVISIBLE (-6575 4350);
FORCEPROP 2 LAST SEC_TYPE 0805
J 0
(-6575 4350);
DISPLAY 1.021277 (-6575 4350);
PAINT ORANGE (-6575 4350);
DISPLAY INVISIBLE (-6575 4350);
FORCEPROP 1 LAST PATH I53
J 0
(-6575 4300);
DISPLAY 0.978723 (-6575 4300);
PAINT WHITE (-6575 4300);
DISPLAY INVISIBLE (-6575 4300);
FORCEPROP 2 LAST CDS_LOCATION C9P4
J 0
(-6575 4250);
DISPLAY 0.617021 (-6575 4250);
PAINT AQUA (-6575 4250);
DISPLAY INVISIBLE (-6575 4250);
FORCEPROP 2 LAST CDS_LIB mstr_discrete
J 0
(-6625 4150);
PAINT ORANGE (-6625 4150);
DISPLAY INVISIBLE (-6625 4150);
FORCEADD CAP..1
(-7000 4150);
FORCEPROP 1 LAST LOCATION C9P7
J 0
(-6950 4250);
DISPLAY 0.617021 (-6950 4250);
PAINT AQUA (-6950 4250);
FORCEPROP 1 LAST VALUE 10UF
J 0
(-6950 4200);
DISPLAY 0.617021 (-6950 4200);
PAINT SKYBLUE (-6950 4200);
FORCEPROP 1 LAST TOLERANCE 10%
J 0
(-6950 4100);
DISPLAY 0.617021 (-6950 4100);
PAINT SKYBLUE (-6950 4100);
FORCEPROP 1 LAST VOLTAGE 16V
J 0
(-6950 4150);
DISPLAY 0.617021 (-6950 4150);
PAINT SKYBLUE (-6950 4150);
FORCEPROP 1 LASTPIN (-7000 4250) $PN 1
J 0
(-6990 4230);
DISPLAY 0.617021 (-6990 4230);
PAINT ORANGE (-6990 4230);
FORCEPROP 1 LAST PART_NUMBER C95333-007
J 0
(-6950 4000);
DISPLAY 0.617021 (-6950 4000);
PAINT BLUE (-6950 4000);
FORCEPROP 1 LAST PACK_TYPE 0805
J 0
(-6950 3950);
DISPLAY 0.617021 (-6950 3950);
PAINT SKYBLUE (-6950 3950);
FORCEPROP 1 LAST MATERIAL X6S
J 0
(-6950 4050);
DISPLAY 0.617021 (-6950 4050);
PAINT SKYBLUE (-6950 4050);
FORCEPROP 1 LASTPIN (-7000 4050) $PN 2
J 0
(-6990 4030);
DISPLAY 0.617021 (-6990 4030);
PAINT ORANGE (-6990 4030);
FORCEPROP 2 LAST ROOM PVCCIN_CPU1_PWR_VR
J 0
(-6950 4300);
DISPLAY 1.361702 (-6950 4300);
PAINT ORANGE (-6950 4300);
DISPLAY INVISIBLE (-6950 4300);
FORCEPROP 2 LAST SEC 1
J 0
(-6950 4350);
DISPLAY 0.680851 (-6950 4350);
PAINT MONO (-6950 4350);
DISPLAY INVISIBLE (-6950 4350);
FORCEPROP 2 LAST SEC_TYPE 0805
J 0
(-6950 4350);
DISPLAY 1.021277 (-6950 4350);
PAINT ORANGE (-6950 4350);
DISPLAY INVISIBLE (-6950 4350);
FORCEPROP 1 LAST PATH I54
J 0
(-6950 4300);
DISPLAY 0.978723 (-6950 4300);
PAINT WHITE (-6950 4300);
DISPLAY INVISIBLE (-6950 4300);
FORCEPROP 2 LAST CDS_LOCATION C9P7
J 0
(-6950 4250);
DISPLAY 0.617021 (-6950 4250);
PAINT AQUA (-6950 4250);
DISPLAY INVISIBLE (-6950 4250);
FORCEPROP 2 LAST CDS_LIB mstr_discrete
J 0
(-7000 4150);
PAINT ORANGE (-7000 4150);
DISPLAY INVISIBLE (-7000 4150);
FORCEADD CAP..1
(-7375 4150);
FORCEPROP 1 LAST TOLERANCE 10%
J 0
(-7325 4100);
DISPLAY 0.617021 (-7325 4100);
PAINT SKYBLUE (-7325 4100);
FORCEPROP 1 LAST VOLTAGE 16V
J 0
(-7325 4150);
DISPLAY 0.617021 (-7325 4150);
PAINT SKYBLUE (-7325 4150);
FORCEPROP 1 LAST LOCATION C9P9
J 0
(-7325 4250);
DISPLAY 0.617021 (-7325 4250);
PAINT AQUA (-7325 4250);
FORCEPROP 1 LAST VALUE 10UF
J 0
(-7325 4200);
DISPLAY 0.617021 (-7325 4200);
PAINT SKYBLUE (-7325 4200);
FORCEPROP 1 LASTPIN (-7375 4250) $PN 1
J 0
(-7365 4230);
DISPLAY 0.617021 (-7365 4230);
PAINT ORANGE (-7365 4230);
FORCEPROP 1 LAST PART_NUMBER C95333-007
J 0
(-7325 4000);
DISPLAY 0.617021 (-7325 4000);
PAINT BLUE (-7325 4000);
FORCEPROP 1 LASTPIN (-7375 4050) $PN 2
J 0
(-7365 4030);
DISPLAY 0.617021 (-7365 4030);
PAINT ORANGE (-7365 4030);
FORCEPROP 1 LAST MATERIAL X6S
J 0
(-7325 4050);
DISPLAY 0.617021 (-7325 4050);
PAINT SKYBLUE (-7325 4050);
FORCEPROP 1 LAST PACK_TYPE 0805
J 0
(-7325 3950);
DISPLAY 0.617021 (-7325 3950);
PAINT SKYBLUE (-7325 3950);
FORCEPROP 2 LAST SEC_TYPE 0805
J 0
(-7325 4350);
DISPLAY 1.021277 (-7325 4350);
PAINT ORANGE (-7325 4350);
DISPLAY INVISIBLE (-7325 4350);
FORCEPROP 2 LAST SEC 1
J 0
(-7325 4350);
DISPLAY 0.680851 (-7325 4350);
PAINT MONO (-7325 4350);
DISPLAY INVISIBLE (-7325 4350);
FORCEPROP 2 LAST ROOM PVCCIN_CPU1_PWR_VR
J 0
(-7325 4300);
DISPLAY 1.361702 (-7325 4300);
PAINT ORANGE (-7325 4300);
DISPLAY INVISIBLE (-7325 4300);
FORCEPROP 1 LAST PATH I55
J 0
(-7325 4300);
DISPLAY 0.978723 (-7325 4300);
PAINT WHITE (-7325 4300);
DISPLAY INVISIBLE (-7325 4300);
FORCEPROP 2 LAST CDS_LOCATION C9P9
J 0
(-7325 4250);
DISPLAY 0.617021 (-7325 4250);
PAINT AQUA (-7325 4250);
DISPLAY INVISIBLE (-7325 4250);
FORCEPROP 2 LAST CDS_LIB mstr_discrete
J 0
(-7375 4150);
PAINT ORANGE (-7375 4150);
DISPLAY INVISIBLE (-7375 4150);
FORCEADD OFFPAGE..1
(-6875 3775);
FORCEPROP 2 LAST $XR0 206 
J 0
(-7157 3775);
DISPLAY 0.638298 (-7157 3775);
PAINT MONO (-7157 3775);
FORCEPROP 2 LASTPIN (-6825 3775) SIG_NAME VR_PVCCIN_CPU1_PWM3
J 0
(-6810 3785);
DISPLAY 0.617021 (-6810 3785);
PAINT ORANGE (-6810 3785);
FORCEPROP 1 LAST COMMENT_BODY TRUE
J 0
(-6750 3675);
DISPLAY 1.680851 (-6750 3675);
PAINT GREEN (-6750 3675);
DISPLAY INVISIBLE (-6750 3675);
FORCEPROP 1 LAST OFFPAGE TRUE
J 0
(-6550 3650);
DISPLAY 1.680851 (-6550 3650);
PAINT GREEN (-6550 3650);
DISPLAY INVISIBLE (-6550 3650);
FORCEPROP 2 LAST CDS_LIB mstr_standard
J 0
(-6875 3775);
DISPLAY 1.936170 (-6875 3775);
PAINT ORANGE (-6875 3775);
DISPLAY INVISIBLE (-6875 3775);
FORCEPROP 2 LAST PATH I56
J 0
(-7120 3825);
DISPLAY 1.021277 (-7120 3825);
PAINT ORANGE (-7120 3825);
DISPLAY INVISIBLE (-7120 3825);
FORCEPROP 2 LAST BOM_COST PROC_VRD_VCCIN_CPU0
J 0
(-7125 3825);
DISPLAY 1.446809 (-7125 3825);
PAINT MONO (-7125 3825);
DISPLAY INVISIBLE (-7125 3825);
FORCEPROP 2 LAST ROOM PVCCIN_CPU1_PWR_VR
J 0
(-7275 3850);
DISPLAY 1.936170 (-7275 3850);
PAINT ORANGE (-7275 3850);
DISPLAY INVISIBLE (-7275 3850);
FORCEADD GND..1
(-7425 3775);
FORCEPROP 3 LASTPIN (-7425 3825) SIG_NAME GND\g
J 0
(-7415 3835);
DISPLAY 0.659574 (-7415 3835);
PAINT MONO (-7415 3835);
DISPLAY INVISIBLE (-7415 3835);
FORCEPROP 1 LAST HDL_POWER GND
J 0
(-7425 3925);
DISPLAY 1.723404 (-7425 3925);
PAINT GREEN (-7425 3925);
DISPLAY INVISIBLE (-7425 3925);
FORCEPROP 1 LAST BODY_TYPE PLUMBING
J 0
(-7470 3732);
DISPLAY 0.340426 (-7470 3732);
PAINT GREEN (-7470 3732);
DISPLAY INVISIBLE (-7470 3732);
FORCEPROP 1 LAST PATH I57
J 0
(-7350 3775);
DISPLAY 0.872340 (-7350 3775);
PAINT AQUA (-7350 3775);
DISPLAY INVISIBLE (-7350 3775);
FORCEPROP 1 LAST SIZE 1B
J 0
(-7350 3725);
DISPLAY 1.723404 (-7350 3725);
PAINT GREEN (-7350 3725);
DISPLAY INVISIBLE (-7350 3725);
FORCEPROP 2 LAST CDS_LIB mstr_symbols
J 0
(-7425 3775);
DISPLAY 1.936170 (-7425 3775);
PAINT ORANGE (-7425 3775);
DISPLAY INVISIBLE (-7425 3775);
FORCEPROP 1 LAST VOLTAGE 0
J 0
(-7425 3775);
PAINT SKYBLUE (-7425 3775);
DISPLAY INVISIBLE (-7425 3775);
FORCEPROP 2 LAST BOM_COST PROC_VRD_VCCIN_CPU0
J 0
(-7800 3850);
DISPLAY 1.446809 (-7800 3850);
PAINT MONO (-7800 3850);
DISPLAY INVISIBLE (-7800 3850);
FORCEPROP 2 LAST ROOM PVCCIN_CPU1_PWR_VR
J 0
(-7975 3850);
DISPLAY 1.936170 (-7975 3850);
PAINT ORANGE (-7975 3850);
DISPLAY INVISIBLE (-7975 3850);
FORCEADD CAP..1
(-6725 1475);
FORCEPROP 1 LAST PART_NUMBER C95333-007
J 0
(-6675 1325);
DISPLAY 0.617021 (-6675 1325);
PAINT BLUE (-6675 1325);
FORCEPROP 1 LAST LOCATION C9P24
J 0
(-6675 1575);
DISPLAY 0.617021 (-6675 1575);
PAINT AQUA (-6675 1575);
FORCEPROP 1 LAST VALUE 10UF
J 0
(-6675 1525);
DISPLAY 0.617021 (-6675 1525);
PAINT SKYBLUE (-6675 1525);
FORCEPROP 1 LAST TOLERANCE 10%
J 0
(-6675 1425);
DISPLAY 0.617021 (-6675 1425);
PAINT SKYBLUE (-6675 1425);
FORCEPROP 1 LAST PACK_TYPE 0805
J 0
(-6675 1275);
DISPLAY 0.617021 (-6675 1275);
PAINT SKYBLUE (-6675 1275);
FORCEPROP 1 LAST VOLTAGE 16V
J 0
(-6675 1475);
DISPLAY 0.617021 (-6675 1475);
PAINT SKYBLUE (-6675 1475);
FORCEPROP 1 LAST MATERIAL X6S
J 0
(-6675 1375);
DISPLAY 0.617021 (-6675 1375);
PAINT SKYBLUE (-6675 1375);
FORCEPROP 1 LASTPIN (-6725 1575) $PN 1
J 0
(-6715 1555);
DISPLAY 0.617021 (-6715 1555);
PAINT ORANGE (-6715 1555);
FORCEPROP 1 LASTPIN (-6725 1375) $PN 2
J 0
(-6715 1355);
DISPLAY 0.617021 (-6715 1355);
PAINT ORANGE (-6715 1355);
FORCEPROP 2 LAST ROOM PVCCIN_CPU1_PWR_VR
J 0
(-6675 1625);
DISPLAY 1.361702 (-6675 1625);
PAINT ORANGE (-6675 1625);
DISPLAY INVISIBLE (-6675 1625);
FORCEPROP 1 LAST PATH I58
J 0
(-6675 1625);
DISPLAY 0.978723 (-6675 1625);
PAINT WHITE (-6675 1625);
DISPLAY INVISIBLE (-6675 1625);
FORCEPROP 2 LAST SEC 1
J 0
(-6675 1675);
DISPLAY 0.680851 (-6675 1675);
PAINT MONO (-6675 1675);
DISPLAY INVISIBLE (-6675 1675);
FORCEPROP 2 LAST SEC_TYPE 0805
J 0
(-6675 1675);
DISPLAY 1.021277 (-6675 1675);
PAINT ORANGE (-6675 1675);
DISPLAY INVISIBLE (-6675 1675);
FORCEPROP 2 LAST CDS_LIB mstr_discrete
J 0
(-6725 1475);
PAINT ORANGE (-6725 1475);
DISPLAY INVISIBLE (-6725 1475);
FORCEADD CAP..1
(-7075 1475);
FORCEPROP 1 LAST LOCATION C9P1
J 0
(-7025 1575);
DISPLAY 0.617021 (-7025 1575);
PAINT AQUA (-7025 1575);
FORCEPROP 1 LASTPIN (-7075 1575) $PN 1
J 0
(-7065 1555);
DISPLAY 0.617021 (-7065 1555);
PAINT ORANGE (-7065 1555);
FORCEPROP 1 LAST VALUE 10UF
J 0
(-7025 1525);
DISPLAY 0.617021 (-7025 1525);
PAINT SKYBLUE (-7025 1525);
FORCEPROP 1 LAST PART_NUMBER C95333-007
J 0
(-7025 1325);
DISPLAY 0.617021 (-7025 1325);
PAINT BLUE (-7025 1325);
FORCEPROP 1 LAST PACK_TYPE 0805
J 0
(-7025 1275);
DISPLAY 0.617021 (-7025 1275);
PAINT SKYBLUE (-7025 1275);
FORCEPROP 1 LASTPIN (-7075 1375) $PN 2
J 0
(-7065 1355);
DISPLAY 0.617021 (-7065 1355);
PAINT ORANGE (-7065 1355);
FORCEPROP 1 LAST TOLERANCE 10%
J 0
(-7025 1425);
DISPLAY 0.617021 (-7025 1425);
PAINT SKYBLUE (-7025 1425);
FORCEPROP 1 LAST VOLTAGE 16V
J 0
(-7025 1475);
DISPLAY 0.617021 (-7025 1475);
PAINT SKYBLUE (-7025 1475);
FORCEPROP 1 LAST MATERIAL X6S
J 0
(-7025 1375);
DISPLAY 0.617021 (-7025 1375);
PAINT SKYBLUE (-7025 1375);
FORCEPROP 2 LAST ROOM PVCCIN_CPU1_PWR_VR
J 0
(-7025 1625);
DISPLAY 1.361702 (-7025 1625);
PAINT ORANGE (-7025 1625);
DISPLAY INVISIBLE (-7025 1625);
FORCEPROP 1 LAST PATH I59
J 0
(-7025 1625);
DISPLAY 0.978723 (-7025 1625);
PAINT WHITE (-7025 1625);
DISPLAY INVISIBLE (-7025 1625);
FORCEPROP 2 LAST CDS_LOCATION C9P1
J 0
(-7025 1575);
DISPLAY 0.617021 (-7025 1575);
PAINT AQUA (-7025 1575);
DISPLAY INVISIBLE (-7025 1575);
FORCEPROP 2 LAST SEC 1
J 0
(-7025 1675);
DISPLAY 0.680851 (-7025 1675);
PAINT MONO (-7025 1675);
DISPLAY INVISIBLE (-7025 1675);
FORCEPROP 2 LAST SEC_TYPE 0805
J 0
(-7025 1675);
DISPLAY 1.021277 (-7025 1675);
PAINT ORANGE (-7025 1675);
DISPLAY INVISIBLE (-7025 1675);
FORCEPROP 2 LAST CDS_LIB mstr_discrete
J 0
(-7075 1475);
PAINT ORANGE (-7075 1475);
DISPLAY INVISIBLE (-7075 1475);
FORCEADD CAP..1
(-7375 1500);
FORCEPROP 1 LAST PART_NUMBER C95333-007
J 0
(-7325 1350);
DISPLAY 0.617021 (-7325 1350);
PAINT BLUE (-7325 1350);
FORCEPROP 1 LAST VALUE 10UF
J 0
(-7325 1550);
DISPLAY 0.617021 (-7325 1550);
PAINT SKYBLUE (-7325 1550);
FORCEPROP 1 LAST LOCATION C9P2
J 0
(-7325 1600);
DISPLAY 0.617021 (-7325 1600);
PAINT AQUA (-7325 1600);
FORCEPROP 1 LASTPIN (-7375 1600) $PN 1
J 0
(-7365 1580);
DISPLAY 0.617021 (-7365 1580);
PAINT ORANGE (-7365 1580);
FORCEPROP 1 LAST TOLERANCE 10%
J 0
(-7325 1450);
DISPLAY 0.617021 (-7325 1450);
PAINT SKYBLUE (-7325 1450);
FORCEPROP 1 LAST PACK_TYPE 0805
J 0
(-7325 1300);
DISPLAY 0.617021 (-7325 1300);
PAINT SKYBLUE (-7325 1300);
FORCEPROP 1 LAST VOLTAGE 16V
J 0
(-7325 1500);
DISPLAY 0.617021 (-7325 1500);
PAINT SKYBLUE (-7325 1500);
FORCEPROP 1 LAST MATERIAL X6S
J 0
(-7325 1400);
DISPLAY 0.617021 (-7325 1400);
PAINT SKYBLUE (-7325 1400);
FORCEPROP 1 LASTPIN (-7375 1400) $PN 2
J 0
(-7365 1380);
DISPLAY 0.617021 (-7365 1380);
PAINT ORANGE (-7365 1380);
FORCEPROP 2 LAST CDS_LOCATION C9P2
J 0
(-7325 1600);
DISPLAY 0.617021 (-7325 1600);
PAINT AQUA (-7325 1600);
DISPLAY INVISIBLE (-7325 1600);
FORCEPROP 2 LAST ROOM PVCCIN_CPU1_PWR_VR
J 0
(-7325 1650);
DISPLAY 1.361702 (-7325 1650);
PAINT ORANGE (-7325 1650);
DISPLAY INVISIBLE (-7325 1650);
FORCEPROP 1 LAST PATH I60
J 0
(-7325 1650);
DISPLAY 0.978723 (-7325 1650);
PAINT WHITE (-7325 1650);
DISPLAY INVISIBLE (-7325 1650);
FORCEPROP 2 LAST SEC 1
J 0
(-7325 1700);
DISPLAY 0.680851 (-7325 1700);
PAINT MONO (-7325 1700);
DISPLAY INVISIBLE (-7325 1700);
FORCEPROP 2 LAST SEC_TYPE 0805
J 0
(-7325 1700);
DISPLAY 1.021277 (-7325 1700);
PAINT ORANGE (-7325 1700);
DISPLAY INVISIBLE (-7325 1700);
FORCEPROP 2 LAST CDS_LIB mstr_discrete
J 0
(-7375 1500);
PAINT ORANGE (-7375 1500);
DISPLAY INVISIBLE (-7375 1500);
FORCEADD OFFPAGE..1
(-6875 1175);
FORCEPROP 2 LAST $XR0 206 
J 0
(-7157 1175);
DISPLAY 0.638298 (-7157 1175);
PAINT MONO (-7157 1175);
FORCEPROP 1 LAST COMMENT_BODY TRUE
J 0
(-6750 1075);
DISPLAY 1.680851 (-6750 1075);
PAINT GREEN (-6750 1075);
DISPLAY INVISIBLE (-6750 1075);
FORCEPROP 1 LAST OFFPAGE TRUE
J 0
(-6550 1050);
DISPLAY 1.680851 (-6550 1050);
PAINT GREEN (-6550 1050);
DISPLAY INVISIBLE (-6550 1050);
FORCEPROP 2 LAST CDS_LIB mstr_standard
J 0
(-6875 1175);
PAINT ORANGE (-6875 1175);
DISPLAY INVISIBLE (-6875 1175);
FORCEPROP 2 LAST BOM_COST PROC_VRD_VCCIN_CPU0
J 0
(-7125 1225);
DISPLAY 1.446809 (-7125 1225);
PAINT MONO (-7125 1225);
DISPLAY INVISIBLE (-7125 1225);
FORCEPROP 2 LAST PATH I61
J 0
(-7120 1225);
DISPLAY 1.021277 (-7120 1225);
PAINT ORANGE (-7120 1225);
DISPLAY INVISIBLE (-7120 1225);
FORCEPROP 2 LAST ROOM PVCCIN_CPU1_PWR_VR
J 0
(-7275 1250);
DISPLAY 1.936170 (-7275 1250);
PAINT ORANGE (-7275 1250);
DISPLAY INVISIBLE (-7275 1250);
FORCEADD VCC_CORE..1
(-7375 1950);
FORCEPROP 3 LASTPIN (-7375 1900) SIG_NAME VR_FET_SW_P12V_STBY_PVCCIN_CPU1\g
J 0
(-7365 1910);
DISPLAY 0.659574 (-7365 1910);
PAINT MONO (-7365 1910);
DISPLAY INVISIBLE (-7365 1910);
FORCEPROP 1 LAST HDL_POWER VR_FET_SW_P12V_STBY_PVCCIN_CPU1
J 1
(-7300 2000);
DISPLAY 0.617021 (-7300 2000);
PAINT GREEN (-7300 2000);
FORCEPROP 2 LAST CDS_LIB mstr_symbols
J 0
(-7375 1950);
PAINT ORANGE (-7375 1950);
DISPLAY INVISIBLE (-7375 1950);
FORCEPROP 1 LAST PATH I62
J 0
(-7325 1975);
DISPLAY 0.872340 (-7325 1975);
PAINT AQUA (-7325 1975);
DISPLAY INVISIBLE (-7325 1975);
FORCEADD GND..1
(-7375 950);
FORCEPROP 3 LASTPIN (-7375 1000) SIG_NAME GND\g
J 0
(-7365 1010);
DISPLAY 0.659574 (-7365 1010);
PAINT MONO (-7365 1010);
DISPLAY INVISIBLE (-7365 1010);
FORCEPROP 1 LAST HDL_POWER GND
J 0
(-7375 1100);
DISPLAY 1.723404 (-7375 1100);
PAINT GREEN (-7375 1100);
DISPLAY INVISIBLE (-7375 1100);
FORCEPROP 1 LAST BODY_TYPE PLUMBING
J 0
(-7420 907);
DISPLAY 0.340426 (-7420 907);
PAINT GREEN (-7420 907);
DISPLAY INVISIBLE (-7420 907);
FORCEPROP 2 LAST BOM_COST PROC_VRD_VCCIN_CPU0
J 0
(-7750 1025);
DISPLAY 1.446809 (-7750 1025);
PAINT MONO (-7750 1025);
DISPLAY INVISIBLE (-7750 1025);
FORCEPROP 2 LAST ROOM PVCCIN_CPU1_PWR_VR
J 0
(-7925 1025);
DISPLAY 1.936170 (-7925 1025);
PAINT ORANGE (-7925 1025);
DISPLAY INVISIBLE (-7925 1025);
FORCEPROP 1 LAST VOLTAGE 0
J 0
(-7375 950);
PAINT SKYBLUE (-7375 950);
DISPLAY INVISIBLE (-7375 950);
FORCEPROP 2 LAST CDS_LIB mstr_symbols
J 0
(-7375 950);
PAINT ORANGE (-7375 950);
DISPLAY INVISIBLE (-7375 950);
FORCEPROP 1 LAST SIZE 1B
J 0
(-7300 900);
DISPLAY 1.723404 (-7300 900);
PAINT GREEN (-7300 900);
DISPLAY INVISIBLE (-7300 900);
FORCEPROP 1 LAST PATH I63
J 0
(-7300 950);
DISPLAY 0.872340 (-7300 950);
PAINT AQUA (-7300 950);
DISPLAY INVISIBLE (-7300 950);
FORCEADD P5V_STBY..1
(-4925 4850);
FORCEPROP 3 LASTPIN (-4925 4800) SIG_NAME P5V_STBY\g
J 0
(-4915 4810);
DISPLAY 0.659574 (-4915 4810);
PAINT MONO (-4915 4810);
DISPLAY INVISIBLE (-4915 4810);
FORCEPROP 1 LAST HDL_POWER P5V_STBY
J 0
(-5225 4725);
DISPLAY 0.872340 (-5225 4725);
PAINT ORANGE (-5225 4725);
DISPLAY INVISIBLE (-5225 4725);
FORCEPROP 1 LAST BODY_TYPE PLUMBING
J 0
(-4970 4807);
DISPLAY 0.340426 (-4970 4807);
PAINT GREEN (-4970 4807);
DISPLAY INVISIBLE (-4970 4807);
FORCEPROP 1 LAST SIZE 1B
J 0
(-4880 4872);
DISPLAY 0.340426 (-4880 4872);
PAINT GREEN (-4880 4872);
DISPLAY INVISIBLE (-4880 4872);
FORCEPROP 2 LAST CDS_LIB mstr_symbols
J 0
(-4925 4850);
PAINT ORANGE (-4925 4850);
DISPLAY INVISIBLE (-4925 4850);
FORCEPROP 1 LAST PATH I64
J 0
(-4880 4852);
DISPLAY 0.340426 (-4880 4852);
PAINT GREEN (-4880 4852);
DISPLAY INVISIBLE (-4880 4852);
FORCEPROP 1 LAST VOLTAGE 5.0V
J 0
(-4970 4807);
DISPLAY 0.340426 (-4970 4807);
PAINT SKYBLUE (-4970 4807);
DISPLAY INVISIBLE (-4970 4807);
FORCEADD P5V_STBY..1
(-5000 2150);
FORCEPROP 3 LASTPIN (-5000 2100) SIG_NAME P5V_STBY\g
J 0
(-4990 2110);
DISPLAY 0.659574 (-4990 2110);
PAINT MONO (-4990 2110);
DISPLAY INVISIBLE (-4990 2110);
FORCEPROP 1 LAST HDL_POWER P5V_STBY
J 0
(-5300 2025);
DISPLAY 0.872340 (-5300 2025);
PAINT ORANGE (-5300 2025);
DISPLAY INVISIBLE (-5300 2025);
FORCEPROP 1 LAST BODY_TYPE PLUMBING
J 0
(-5045 2107);
DISPLAY 0.340426 (-5045 2107);
PAINT GREEN (-5045 2107);
DISPLAY INVISIBLE (-5045 2107);
FORCEPROP 1 LAST VOLTAGE 5.0V
J 0
(-5045 2107);
DISPLAY 0.340426 (-5045 2107);
PAINT SKYBLUE (-5045 2107);
DISPLAY INVISIBLE (-5045 2107);
FORCEPROP 1 LAST SIZE 1B
J 0
(-4955 2172);
DISPLAY 0.340426 (-4955 2172);
PAINT GREEN (-4955 2172);
DISPLAY INVISIBLE (-4955 2172);
FORCEPROP 2 LAST CDS_LIB mstr_symbols
J 0
(-5000 2150);
PAINT ORANGE (-5000 2150);
DISPLAY INVISIBLE (-5000 2150);
FORCEPROP 1 LAST PATH I65
J 0
(-4955 2152);
DISPLAY 0.340426 (-4955 2152);
PAINT GREEN (-4955 2152);
DISPLAY INVISIBLE (-4955 2152);
FORCEADD CAP_A..1
(-400 3400);
FORCEPROP 1 LAST VOLTAGE 4V
J 0
(-350 3400);
DISPLAY 0.617021 (-350 3400);
PAINT SKYBLUE (-350 3400);
FORCEPROP 1 LAST PACK_TYPE 0603V
J 0
(-350 3200);
DISPLAY 0.617021 (-350 3200);
PAINT SKYBLUE (-350 3200);
FORCEPROP 1 LAST VALUE 22.0UF
J 0
(-350 3450);
DISPLAY 0.617021 (-350 3450);
PAINT SKYBLUE (-350 3450);
FORCEPROP 1 LAST PART_NUMBER E15431-004
J 0
(-350 3250);
DISPLAY 0.617021 (-350 3250);
PAINT BLUE (-350 3250);
FORCEPROP 1 LASTPIN (-400 3500) $PN 1
J 0
(-390 3480);
DISPLAY 0.617021 (-390 3480);
PAINT ORANGE (-390 3480);
FORCEPROP 1 LAST MATERIAL X6S
J 0
(-350 3300);
DISPLAY 0.617021 (-350 3300);
PAINT SKYBLUE (-350 3300);
FORCEPROP 1 LASTPIN (-400 3300) $PN 2
J 0
(-390 3280);
DISPLAY 0.617021 (-390 3280);
PAINT ORANGE (-390 3280);
FORCEPROP 1 LAST TOLERANCE 20%
J 0
(-350 3350);
DISPLAY 0.617021 (-350 3350);
PAINT SKYBLUE (-350 3350);
FORCEPROP 1 LAST LOCATION C9P10
J 0
(-350 3500);
DISPLAY 0.617021 (-350 3500);
PAINT AQUA (-350 3500);
FORCEPROP 2 LAST SEC_TYPE 0603V
J 0
(-350 3600);
DISPLAY 1.021277 (-350 3600);
PAINT ORANGE (-350 3600);
DISPLAY INVISIBLE (-350 3600);
FORCEPROP 2 LAST SEC 1
J 0
(-350 3600);
DISPLAY 0.680851 (-350 3600);
PAINT MONO (-350 3600);
DISPLAY INVISIBLE (-350 3600);
FORCEPROP 2 LAST CDS_SEC 1
J 0
(-350 3550);
PAINT ORANGE (-350 3550);
DISPLAY INVISIBLE (-350 3550);
FORCEPROP 1 LAST PATH I66
J 0
(-350 3550);
DISPLAY 0.978723 (-350 3550);
PAINT WHITE (-350 3550);
DISPLAY INVISIBLE (-350 3550);
FORCEPROP 2 LAST CDS_LOCATION C9P10
J 0
(-350 3500);
DISPLAY 0.617021 (-350 3500);
PAINT AQUA (-350 3500);
DISPLAY INVISIBLE (-350 3500);
FORCEPROP 2 LAST CDS_LIB dev_discrete
J 0
(-400 3400);
PAINT ORANGE (-400 3400);
DISPLAY INVISIBLE (-400 3400);
FORCEADD CAP_A..1
(-350 800);
FORCEPROP 1 LAST VALUE 22.0UF
J 0
(-300 850);
DISPLAY 0.617021 (-300 850);
PAINT SKYBLUE (-300 850);
FORCEPROP 1 LAST MATERIAL X6S
J 0
(-300 700);
DISPLAY 0.617021 (-300 700);
PAINT SKYBLUE (-300 700);
FORCEPROP 1 LAST PART_NUMBER E15431-004
J 0
(-300 650);
DISPLAY 0.617021 (-300 650);
PAINT BLUE (-300 650);
FORCEPROP 1 LAST PACK_TYPE 0603V
J 0
(-300 600);
DISPLAY 0.617021 (-300 600);
PAINT SKYBLUE (-300 600);
FORCEPROP 1 LAST VOLTAGE 4V
J 0
(-300 800);
DISPLAY 0.617021 (-300 800);
PAINT SKYBLUE (-300 800);
FORCEPROP 1 LAST TOLERANCE 20%
J 0
(-300 750);
DISPLAY 0.617021 (-300 750);
PAINT SKYBLUE (-300 750);
FORCEPROP 1 LASTPIN (-350 900) $PN 1
J 0
(-340 880);
DISPLAY 0.617021 (-340 880);
PAINT ORANGE (-340 880);
FORCEPROP 1 LASTPIN (-350 700) $PN 2
J 0
(-340 680);
DISPLAY 0.617021 (-340 680);
PAINT ORANGE (-340 680);
FORCEPROP 1 LAST LOCATION C9R2
J 0
(-300 900);
DISPLAY 0.617021 (-300 900);
PAINT AQUA (-300 900);
FORCEPROP 2 LAST SEC_TYPE 0603V
J 0
(-300 1000);
DISPLAY 1.021277 (-300 1000);
PAINT ORANGE (-300 1000);
DISPLAY INVISIBLE (-300 1000);
FORCEPROP 2 LAST SEC 1
J 0
(-300 1000);
DISPLAY 0.680851 (-300 1000);
PAINT MONO (-300 1000);
DISPLAY INVISIBLE (-300 1000);
FORCEPROP 1 LAST PATH I67
J 0
(-300 950);
DISPLAY 0.978723 (-300 950);
PAINT WHITE (-300 950);
DISPLAY INVISIBLE (-300 950);
FORCEPROP 2 LAST CDS_SEC 1
J 0
(-300 950);
PAINT ORANGE (-300 950);
DISPLAY INVISIBLE (-300 950);
FORCEPROP 2 LAST CDS_LOCATION C9R2
J 0
(-300 900);
DISPLAY 0.617021 (-300 900);
PAINT AQUA (-300 900);
DISPLAY INVISIBLE (-300 900);
FORCEPROP 2 LAST CDS_LIB dev_discrete
J 0
(-350 800);
PAINT ORANGE (-350 800);
DISPLAY INVISIBLE (-350 800);
FORCEADD RES..2
(-1000 2575);
FORCEPROP 1 LAST WATTAGE 1/10W
J 0
(-960 2550);
DISPLAY 0.617021 (-960 2550);
PAINT SKYBLUE (-960 2550);
FORCEPROP 1 LAST MATERIAL CHIP
J 0
(-960 2500);
DISPLAY 0.617021 (-960 2500);
PAINT SKYBLUE (-960 2500);
FORCEPROP 1 LAST PART_NUMBER G22026-038
J 0
(-960 2450);
DISPLAY 0.617021 (-960 2450);
PAINT BLUE (-960 2450);
FORCEPROP 1 LAST LOCATION R1E3
J 0
(-955 2700);
DISPLAY 0.617021 (-955 2700);
PAINT AQUA (-955 2700);
FORCEPROP 1 LAST VALUE 100.0
J 0
(-955 2650);
DISPLAY 0.617021 (-955 2650);
PAINT SKYBLUE (-955 2650);
FORCEPROP 1 LAST TOLERANCE 1%
J 0
(-955 2600);
DISPLAY 0.617021 (-955 2600);
PAINT SKYBLUE (-955 2600);
FORCEPROP 1 LASTPIN (-1000 2675) $PN 1
J 0
(-995 2637);
DISPLAY 0.617021 (-995 2637);
PAINT ORANGE (-995 2637);
FORCEPROP 1 LAST PACK_TYPE 0603
J 0
(-960 2400);
DISPLAY 0.617021 (-960 2400);
PAINT SKYBLUE (-960 2400);
FORCEPROP 1 LASTPIN (-1000 2475) $PN 2
J 0
(-995 2485);
DISPLAY 0.617021 (-995 2485);
PAINT ORANGE (-995 2485);
FORCEPROP 2 LAST SEC_TYPE 0603
J 0
(-935 2810);
DISPLAY 1.021277 (-935 2810);
PAINT ORANGE (-935 2810);
DISPLAY INVISIBLE (-935 2810);
FORCEPROP 2 LAST SEC 1
J 0
(-935 2810);
DISPLAY 0.680851 (-935 2810);
PAINT MONO (-935 2810);
DISPLAY INVISIBLE (-935 2810);
FORCEPROP 2 LAST BOM_COST PROC_VRD_VCCIN_CPU0
J 0
(-950 2750);
PAINT MONO (-950 2750);
DISPLAY INVISIBLE (-950 2750);
FORCEPROP 2 LAST CDS_LOCATION R1E3
J 0
(-955 2700);
DISPLAY 0.617021 (-955 2700);
PAINT AQUA (-955 2700);
DISPLAY INVISIBLE (-955 2700);
FORCEPROP 1 LAST PATH I7
J 0
(-950 2750);
DISPLAY 0.978723 (-950 2750);
PAINT WHITE (-950 2750);
DISPLAY INVISIBLE (-950 2750);
FORCEPROP 2 LAST ROOM PVCCIN_CPU1_DECAP_VR
J 0
(-950 2750);
PAINT MONO (-950 2750);
DISPLAY INVISIBLE (-950 2750);
FORCEPROP 2 LAST CDS_LIB mstr_discrete
J 0
(-1000 2575);
PAINT ORANGE (-1000 2575);
DISPLAY INVISIBLE (-1000 2575);
FORCEADD OFFPAGE..2
(-900 4425);
FORCEPROP 2 LAST $XR0 206 
J 0
(-711 4425);
DISPLAY 0.638298 (-711 4425);
PAINT MONO (-711 4425);
FORCEPROP 1 LAST COMMENT_BODY TRUE
J 0
(-945 4330);
DISPLAY 1.723404 (-945 4330);
PAINT GREEN (-945 4330);
DISPLAY INVISIBLE (-945 4330);
FORCEPROP 1 LAST OFFPAGE TRUE
J 0
(-575 4300);
DISPLAY 1.723404 (-575 4300);
PAINT GREEN (-575 4300);
DISPLAY INVISIBLE (-575 4300);
FORCEPROP 2 LAST BOM_COST PROC_VRD_VCCIN_CPU0
J 0
(-700 4475);
DISPLAY 1.446809 (-700 4475);
PAINT MONO (-700 4475);
DISPLAY INVISIBLE (-700 4475);
FORCEPROP 2 LAST PATH I70
J 0
(-725 4500);
DISPLAY 1.021277 (-725 4500);
PAINT ORANGE (-725 4500);
DISPLAY INVISIBLE (-725 4500);
FORCEPROP 2 LAST CDS_LIB mstr_standard
J 0
(-900 4425);
PAINT ORANGE (-900 4425);
DISPLAY INVISIBLE (-900 4425);
FORCEPROP 2 LAST ROOM PVCCIN_CPU1_PWR_VR
J 0
(-1300 4500);
DISPLAY 1.936170 (-1300 4500);
PAINT ORANGE (-1300 4500);
DISPLAY INVISIBLE (-1300 4500);
FORCEADD IR354XX..1
(-3250 1275);
FORCEPROP 1 LAST PART_NUMBER H73688-001
J 0
(-3325 575);
DISPLAY 0.617021 (-3325 575);
PAINT BLUE (-3325 575);
FORCEPROP 2 LASTPIN (-3750 1075) $PN 39
J 2
(-3760 1085);
DISPLAY 0.617021 (-3760 1085);
PAINT ORANGE (-3760 1085);
FORCEPROP 2 LASTPIN (-3750 975) $PN 33
J 2
(-3760 985);
DISPLAY 0.617021 (-3760 985);
PAINT ORANGE (-3760 985);
FORCEPROP 2 LASTPIN (-3750 1775) $PN 30
J 2
(-3760 1785);
DISPLAY 0.617021 (-3760 1785);
PAINT ORANGE (-3760 1785);
FORCEPROP 2 LASTPIN (-3750 1725) $PN 25
J 2
(-3760 1735);
DISPLAY 0.617021 (-3760 1735);
PAINT ORANGE (-3760 1735);
FORCEPROP 2 LASTPIN (-3750 925) $PN 32
J 2
(-3760 935);
DISPLAY 0.617021 (-3760 935);
PAINT ORANGE (-3760 935);
FORCEPROP 2 LASTPIN (-2750 825) $PN 40
J 0
(-2740 835);
DISPLAY 0.617021 (-2740 835);
PAINT ORANGE (-2740 835);
FORCEPROP 2 LASTPIN (-2750 775) $PN 7
J 0
(-2740 785);
DISPLAY 0.617021 (-2740 785);
PAINT ORANGE (-2740 785);
FORCEPROP 2 LASTPIN (-2750 975) $PN 10
J 0
(-2740 985);
DISPLAY 0.617021 (-2740 985);
PAINT ORANGE (-2740 985);
FORCEPROP 2 LASTPIN (-2750 1325) $PN 36
J 0
(-2740 1335);
DISPLAY 0.617021 (-2740 1335);
PAINT ORANGE (-2740 1335);
FORCEPROP 1 LAST MATERIAL IC
J 0
(-3700 2025);
DISPLAY 0.617021 (-3700 2025);
PAINT SKYBLUE (-3700 2025);
FORCEPROP 2 LASTPIN (-2750 1625) $PN 37
J 0
(-2740 1635);
DISPLAY 0.617021 (-2740 1635);
PAINT ORANGE (-2740 1635);
FORCEPROP 2 LASTPIN (-2750 1825) $PN 38
J 0
(-2740 1835);
DISPLAY 0.617021 (-2740 1835);
PAINT ORANGE (-2740 1835);
FORCEPROP 2 LASTPIN (-2750 725) $PN 5
J 0
(-2740 735);
DISPLAY 0.617021 (-2740 735);
PAINT ORANGE (-2740 735);
FORCEPROP 1 LAST VALUE IR35411
J 1
(-3250 1900);
DISPLAY 0.617021 (-3250 1900);
PAINT SKYBLUE (-3250 1900);
FORCEPROP 1 LAST LOCATION EU1D1
J 0
(-3650 2000);
DISPLAY 0.617021 (-3650 2000);
PAINT AQUA (-3650 2000);
FORCEPROP 2 LASTPIN (-3750 1825) $PN 3
J 2
(-3760 1835);
DISPLAY 0.617021 (-3760 1835);
PAINT ORANGE (-3760 1835);
FORCEPROP 2 LASTPIN (-3750 1625) $PN 4
J 2
(-3760 1635);
DISPLAY 0.617021 (-3760 1635);
PAINT ORANGE (-3760 1635);
FORCEPROP 2 LASTPIN (-3750 1525) $PN 35
J 2
(-3760 1535);
DISPLAY 0.617021 (-3760 1535);
PAINT ORANGE (-3760 1535);
FORCEPROP 2 LASTPIN (-3750 1425) $PN 1
J 2
(-3760 1435);
DISPLAY 0.617021 (-3760 1435);
PAINT ORANGE (-3760 1435);
FORCEPROP 2 LASTPIN (-3750 1325) $PN 41
J 2
(-3760 1335);
DISPLAY 0.617021 (-3760 1335);
PAINT ORANGE (-3760 1335);
FORCEPROP 2 LASTPIN (-3750 1275) $PN 6
J 2
(-3760 1285);
DISPLAY 0.617021 (-3760 1285);
PAINT ORANGE (-3760 1285);
FORCEPROP 2 LASTPIN (-3750 1175) $PN 34
J 2
(-3760 1185);
DISPLAY 0.617021 (-3760 1185);
PAINT ORANGE (-3760 1185);
FORCEPROP 2 LASTPIN (-2750 875) $PN 2
J 0
(-2740 885);
DISPLAY 0.617021 (-2740 885);
PAINT ORANGE (-2740 885);
FORCEPROP 2 LASTPIN (-2750 1575) $PN 31
J 0
(-2740 1585);
DISPLAY 0.617021 (-2740 1585);
PAINT ORANGE (-2740 1585);
FORCEPROP 2 LAST SEC_TYPE SM
J 0
(-3250 2075);
DISPLAY 1.021277 (-3250 2075);
PAINT ORANGE (-3250 2075);
DISPLAY INVISIBLE (-3250 2075);
FORCEPROP 2 LAST SEC 1
J 0
(-3250 2075);
DISPLAY 0.680851 (-3250 2075);
PAINT MONO (-3250 2075);
DISPLAY INVISIBLE (-3250 2075);
FORCEPROP 1 LAST PACK_TYPE SM
J 0
(-3700 2125);
PAINT SKYBLUE (-3700 2125);
DISPLAY INVISIBLE (-3700 2125);
FORCEPROP 2 LAST ROOM PVCCIN_CPU1_PWR_VR
J 0
(-3650 2050);
DISPLAY 1.361702 (-3650 2050);
PAINT ORANGE (-3650 2050);
DISPLAY INVISIBLE (-3650 2050);
FORCEPROP 1 LAST PATH I71
J 0
(-3250 2025);
PAINT GREEN (-3250 2025);
DISPLAY INVISIBLE (-3250 2025);
FORCEPROP 2 LAST CDS_LIB mstr_discrete
J 0
(-3250 1275);
PAINT ORANGE (-3250 1275);
DISPLAY INVISIBLE (-3250 1275);
FORCEPROP 2 LAST CDS_LOCATION EU1D1
J 0
(-3650 2000);
DISPLAY 0.617021 (-3650 2000);
PAINT AQUA (-3650 2000);
DISPLAY INVISIBLE (-3650 2000);
FORCEADD OFFPAGE..2
(-850 2125);
FORCEPROP 2 LAST $XR0 206 
J 0
(-661 2125);
DISPLAY 0.638298 (-661 2125);
PAINT MONO (-661 2125);
FORCEPROP 1 LAST COMMENT_BODY TRUE
J 0
(-895 2030);
DISPLAY 1.723404 (-895 2030);
PAINT GREEN (-895 2030);
DISPLAY INVISIBLE (-895 2030);
FORCEPROP 1 LAST OFFPAGE TRUE
J 0
(-525 2000);
DISPLAY 1.723404 (-525 2000);
PAINT GREEN (-525 2000);
DISPLAY INVISIBLE (-525 2000);
FORCEPROP 2 LAST BOM_COST PROC_VRD_VCCIN_CPU0
J 0
(-650 2175);
DISPLAY 1.446809 (-650 2175);
PAINT MONO (-650 2175);
DISPLAY INVISIBLE (-650 2175);
FORCEPROP 2 LAST PATH I72
J 0
(-675 2200);
DISPLAY 1.021277 (-675 2200);
PAINT ORANGE (-675 2200);
DISPLAY INVISIBLE (-675 2200);
FORCEPROP 2 LAST CDS_LIB mstr_standard
J 0
(-850 2125);
PAINT ORANGE (-850 2125);
DISPLAY INVISIBLE (-850 2125);
FORCEPROP 2 LAST ROOM PVCCIN_CPU1_PWR_VR
J 0
(-1250 2200);
DISPLAY 1.936170 (-1250 2200);
PAINT ORANGE (-1250 2200);
DISPLAY INVISIBLE (-1250 2200);
FORCEADD RES..2
(-625 1450);
FORCEPROP 1 LAST PART_NUMBER G21796-187
J 0
(-585 1325);
DISPLAY 0.617021 (-585 1325);
PAINT BLUE (-585 1325);
FORCEPROP 1 LASTPIN (-625 1350) $PN 2
J 0
(-620 1360);
DISPLAY 0.617021 (-620 1360);
PAINT ORANGE (-620 1360);
FORCEPROP 1 LASTPIN (-625 1550) $PN 1
J 0
(-620 1512);
DISPLAY 0.617021 (-620 1512);
PAINT ORANGE (-620 1512);
FORCEPROP 1 LAST TOLERANCE 1%
J 0
(-580 1475);
DISPLAY 0.617021 (-580 1475);
PAINT SKYBLUE (-580 1475);
FORCEPROP 1 LAST WATTAGE 1/16W
J 0
(-585 1425);
DISPLAY 0.617021 (-585 1425);
PAINT SKYBLUE (-585 1425);
FORCEPROP 1 LAST LOCATION R1D54
J 0
(-580 1575);
DISPLAY 0.617021 (-580 1575);
PAINT AQUA (-580 1575);
FORCEPROP 1 LAST VALUE 68.1K
J 0
(-580 1525);
DISPLAY 0.617021 (-580 1525);
PAINT SKYBLUE (-580 1525);
FORCEPROP 1 LAST MATERIAL EMPTY
J 0
(-585 1375);
DISPLAY 0.617021 (-585 1375);
PAINT RED (-585 1375);
FORCEPROP 1 LAST PACK_TYPE 0402
J 0
(-585 1275);
DISPLAY 0.617021 (-585 1275);
PAINT SKYBLUE (-585 1275);
FORCEPROP 1 LAST PATH I75
J 0
(-575 1625);
DISPLAY 0.978723 (-575 1625);
PAINT WHITE (-575 1625);
DISPLAY INVISIBLE (-575 1625);
FORCEPROP 2 LAST $SEC 1
J 0
(-575 1675);
PAINT MONO (-575 1675);
DISPLAY INVISIBLE (-575 1675);
FORCEPROP 2 LAST CDS_SEC 1
J 0
(-575 1675);
PAINT MONO (-575 1675);
DISPLAY INVISIBLE (-575 1675);
FORCEPROP 2 LAST CDS_LIB mstr_discrete
J 0
(-625 1450);
PAINT ORANGE (-625 1450);
DISPLAY INVISIBLE (-625 1450);
FORCEADD RES..2
(-700 4075);
FORCEPROP 1 LAST LOCATION R1D55
J 0
(-655 4200);
DISPLAY 0.617021 (-655 4200);
PAINT AQUA (-655 4200);
FORCEPROP 1 LAST VALUE 68.1K
J 0
(-655 4150);
DISPLAY 0.617021 (-655 4150);
PAINT SKYBLUE (-655 4150);
FORCEPROP 1 LAST TOLERANCE 1%
J 0
(-655 4100);
DISPLAY 0.617021 (-655 4100);
PAINT SKYBLUE (-655 4100);
FORCEPROP 1 LASTPIN (-700 4175) $PN 1
J 0
(-695 4137);
DISPLAY 0.617021 (-695 4137);
PAINT ORANGE (-695 4137);
FORCEPROP 1 LAST PART_NUMBER G21796-187
J 0
(-660 3950);
DISPLAY 0.617021 (-660 3950);
PAINT BLUE (-660 3950);
FORCEPROP 1 LAST MATERIAL EMPTY
J 0
(-660 4000);
DISPLAY 0.617021 (-660 4000);
PAINT RED (-660 4000);
FORCEPROP 1 LAST PACK_TYPE 0402
J 0
(-660 3900);
DISPLAY 0.617021 (-660 3900);
PAINT SKYBLUE (-660 3900);
FORCEPROP 1 LAST WATTAGE 1/16W
J 0
(-660 4050);
DISPLAY 0.617021 (-660 4050);
PAINT SKYBLUE (-660 4050);
FORCEPROP 1 LASTPIN (-700 3975) $PN 2
J 0
(-695 3985);
DISPLAY 0.617021 (-695 3985);
PAINT ORANGE (-695 3985);
FORCEPROP 2 LAST CDS_SEC 1
J 0
(-650 4300);
PAINT MONO (-650 4300);
DISPLAY INVISIBLE (-650 4300);
FORCEPROP 2 LAST $SEC 1
J 0
(-650 4300);
PAINT MONO (-650 4300);
DISPLAY INVISIBLE (-650 4300);
FORCEPROP 1 LAST PATH I76
J 0
(-650 4250);
DISPLAY 0.978723 (-650 4250);
PAINT WHITE (-650 4250);
DISPLAY INVISIBLE (-650 4250);
FORCEPROP 2 LAST CDS_LIB mstr_discrete
J 0
(-700 4075);
PAINT ORANGE (-700 4075);
DISPLAY INVISIBLE (-700 4075);
FORCEADD GND..1
(-700 3825);
FORCEPROP 3 LASTPIN (-700 3875) SIG_NAME GND\g
J 0
(-690 3885);
DISPLAY 0.659574 (-690 3885);
PAINT MONO (-690 3885);
DISPLAY INVISIBLE (-690 3885);
FORCEPROP 1 LAST HDL_POWER GND
J 0
(-700 3975);
DISPLAY 1.723404 (-700 3975);
PAINT GREEN (-700 3975);
DISPLAY INVISIBLE (-700 3975);
FORCEPROP 1 LAST BODY_TYPE PLUMBING
J 0
(-745 3782);
DISPLAY 0.340426 (-745 3782);
PAINT GREEN (-745 3782);
DISPLAY INVISIBLE (-745 3782);
FORCEPROP 1 LAST VOLTAGE 0
J 0
(-700 3825);
PAINT SKYBLUE (-700 3825);
DISPLAY INVISIBLE (-700 3825);
FORCEPROP 2 LAST CDS_LIB mstr_symbols
J 0
(-700 3825);
PAINT ORANGE (-700 3825);
DISPLAY INVISIBLE (-700 3825);
FORCEPROP 1 LAST SIZE 1B
J 0
(-625 3775);
DISPLAY 1.723404 (-625 3775);
PAINT GREEN (-625 3775);
DISPLAY INVISIBLE (-625 3775);
FORCEPROP 1 LAST PATH I77
J 0
(-625 3825);
DISPLAY 0.872340 (-625 3825);
PAINT AQUA (-625 3825);
DISPLAY INVISIBLE (-625 3825);
FORCEPROP 2 LAST BOM_COST PROC_VRD_VCCIN_CPU0
J 0
(-1075 3900);
DISPLAY 1.446809 (-1075 3900);
PAINT MONO (-1075 3900);
DISPLAY INVISIBLE (-1075 3900);
FORCEPROP 2 LAST ROOM PVCCIN_CPU1_PWR_VR
J 0
(-1250 3900);
DISPLAY 1.936170 (-1250 3900);
PAINT ORANGE (-1250 3900);
DISPLAY INVISIBLE (-1250 3900);
FORCEADD GND..1
(-625 1225);
FORCEPROP 3 LASTPIN (-625 1275) SIG_NAME GND\g
J 0
(-615 1285);
DISPLAY 0.659574 (-615 1285);
PAINT MONO (-615 1285);
DISPLAY INVISIBLE (-615 1285);
FORCEPROP 1 LAST HDL_POWER GND
J 0
(-625 1375);
DISPLAY 1.723404 (-625 1375);
PAINT GREEN (-625 1375);
DISPLAY INVISIBLE (-625 1375);
FORCEPROP 1 LAST BODY_TYPE PLUMBING
J 0
(-670 1182);
DISPLAY 0.340426 (-670 1182);
PAINT GREEN (-670 1182);
DISPLAY INVISIBLE (-670 1182);
FORCEPROP 1 LAST VOLTAGE 0
J 0
(-625 1225);
PAINT SKYBLUE (-625 1225);
DISPLAY INVISIBLE (-625 1225);
FORCEPROP 1 LAST SIZE 1B
J 0
(-550 1175);
DISPLAY 1.723404 (-550 1175);
PAINT GREEN (-550 1175);
DISPLAY INVISIBLE (-550 1175);
FORCEPROP 2 LAST CDS_LIB mstr_symbols
J 0
(-625 1225);
PAINT ORANGE (-625 1225);
DISPLAY INVISIBLE (-625 1225);
FORCEPROP 1 LAST PATH I78
J 0
(-550 1225);
DISPLAY 0.872340 (-550 1225);
PAINT AQUA (-550 1225);
DISPLAY INVISIBLE (-550 1225);
FORCEPROP 2 LAST BOM_COST PROC_VRD_VCCIN_CPU0
J 0
(-1000 1300);
DISPLAY 1.446809 (-1000 1300);
PAINT MONO (-1000 1300);
DISPLAY INVISIBLE (-1000 1300);
FORCEPROP 2 LAST ROOM PVCCIN_CPU1_PWR_VR
J 0
(-1175 1300);
DISPLAY 1.936170 (-1175 1300);
PAINT ORANGE (-1175 1300);
DISPLAY INVISIBLE (-1175 1300);
FORCEADD GND..1
(-3975 3125);
FORCEPROP 3 LASTPIN (-3975 3175) SIG_NAME GND\g
J 0
(-3965 3185);
DISPLAY 0.659574 (-3965 3185);
PAINT MONO (-3965 3185);
DISPLAY INVISIBLE (-3965 3185);
FORCEPROP 1 LAST HDL_POWER GND
J 0
(-3975 3275);
DISPLAY 1.723404 (-3975 3275);
PAINT GREEN (-3975 3275);
DISPLAY INVISIBLE (-3975 3275);
FORCEPROP 1 LAST BODY_TYPE PLUMBING
J 0
(-4020 3082);
DISPLAY 0.340426 (-4020 3082);
PAINT GREEN (-4020 3082);
DISPLAY INVISIBLE (-4020 3082);
FORCEPROP 2 LAST ROOM PVCCIN_CPU0_PWR_VR
J 0
(-4525 3200);
DISPLAY 1.936170 (-4525 3200);
PAINT ORANGE (-4525 3200);
DISPLAY INVISIBLE (-4525 3200);
FORCEPROP 2 LAST BOM_COST PROC_VRD_VCCIN_CPU0
J 0
(-4350 3200);
DISPLAY 1.446809 (-4350 3200);
PAINT MONO (-4350 3200);
DISPLAY INVISIBLE (-4350 3200);
FORCEPROP 1 LAST SIZE 1B
J 0
(-3900 3075);
DISPLAY 1.723404 (-3900 3075);
PAINT GREEN (-3900 3075);
DISPLAY INVISIBLE (-3900 3075);
FORCEPROP 1 LAST VOLTAGE 0
J 0
(-3975 3125);
PAINT SKYBLUE (-3975 3125);
DISPLAY INVISIBLE (-3975 3125);
FORCEPROP 1 LAST PATH I79
J 0
(-3900 3125);
DISPLAY 0.872340 (-3900 3125);
PAINT AQUA (-3900 3125);
DISPLAY INVISIBLE (-3900 3125);
FORCEPROP 2 LAST CDS_LIB mstr_symbols
J 0
(-3975 3125);
PAINT MONO (-3975 3125);
DISPLAY INVISIBLE (-3975 3125);
FORCEADD PVCCIN_CPU1..1
(-400 3700);
FORCEPROP 3 LASTPIN (-400 3650) SIG_NAME PVCCIN_CPU1\g
J 0
(-390 3660);
DISPLAY 0.659574 (-390 3660);
PAINT MONO (-390 3660);
DISPLAY INVISIBLE (-390 3660);
FORCEPROP 1 LAST HDL_POWER PVCCIN_CPU1
J 1
(-400 3750);
DISPLAY 0.872340 (-400 3750);
PAINT GREEN (-400 3750);
DISPLAY INVISIBLE (-400 3750);
FORCEPROP 1 LAST BODY_TYPE PLUMBING
J 0
(-445 3657);
DISPLAY 0.340426 (-445 3657);
PAINT GREEN (-445 3657);
DISPLAY INVISIBLE (-445 3657);
FORCEPROP 2 LAST CDS_LIB mstr_symbols
J 0
(-400 3700);
PAINT ORANGE (-400 3700);
DISPLAY INVISIBLE (-400 3700);
FORCEPROP 1 LAST VOLTAGE 2.0V
J 0
(-445 3657);
DISPLAY 0.340426 (-445 3657);
PAINT SKYBLUE (-445 3657);
DISPLAY INVISIBLE (-445 3657);
FORCEPROP 1 LAST PATH I8
J 0
(-350 3725);
DISPLAY 0.872340 (-350 3725);
PAINT AQUA (-350 3725);
DISPLAY INVISIBLE (-350 3725);
FORCEADD CAP_A..1
(-3975 3375);
FORCEPROP 1 LAST MATERIAL X7R
J 0
(-3925 3275);
DISPLAY 0.617021 (-3925 3275);
PAINT SKYBLUE (-3925 3275);
FORCEPROP 1 LAST TOLERANCE 10%
J 0
(-3925 3325);
DISPLAY 0.617021 (-3925 3325);
PAINT SKYBLUE (-3925 3325);
FORCEPROP 1 LAST VOLTAGE 16V
J 0
(-3925 3375);
DISPLAY 0.617021 (-3925 3375);
PAINT SKYBLUE (-3925 3375);
FORCEPROP 1 LAST LOCATION CT16
J 0
(-3925 3475);
DISPLAY 0.617021 (-3925 3475);
PAINT AQUA (-3925 3475);
FORCEPROP 1 LAST VALUE 0.1UF
J 0
(-3925 3425);
DISPLAY 0.617021 (-3925 3425);
PAINT SKYBLUE (-3925 3425);
FORCEPROP 1 LAST PART_NUMBER A36096-030
J 0
(-3925 3225);
DISPLAY 0.617021 (-3925 3225);
PAINT BLUE (-3925 3225);
FORCEPROP 1 LAST PACK_TYPE 0402V
J 0
(-3925 3175);
DISPLAY 0.617021 (-3925 3175);
PAINT SKYBLUE (-3925 3175);
FORCEPROP 0 LAST STATUS NOPOP
J 0
(-4275 3350);
DISPLAY 1.021277 (-4275 3350);
PAINT ORANGE (-4275 3350);
FORCEPROP 2 LAST ROOM PVCCIN_CPU0_PWR_VR
J 0
(-3925 3525);
DISPLAY 1.361702 (-3925 3525);
PAINT ORANGE (-3925 3525);
DISPLAY INVISIBLE (-3925 3525);
FORCEPROP 1 LAST PATH I80
J 0
(-3925 3525);
DISPLAY 0.978723 (-3925 3525);
PAINT WHITE (-3925 3525);
DISPLAY INVISIBLE (-3925 3525);
FORCEPROP 2 LAST CDS_LIB dev_discrete
J 0
(-3975 3375);
PAINT MONO (-3975 3375);
DISPLAY INVISIBLE (-3975 3375);
FORCEPROP 1 LASTPIN (-3975 3475) $PN 1
J 0
(-3965 3455);
DISPLAY 0.787234 (-3965 3455);
PAINT ORANGE (-3965 3455);
DISPLAY INVISIBLE (-3965 3455);
FORCEPROP 1 LASTPIN (-3975 3275) $PN 2
J 0
(-3965 3255);
DISPLAY 0.787234 (-3965 3255);
PAINT ORANGE (-3965 3255);
DISPLAY INVISIBLE (-3965 3255);
FORCEADD CAP..1
(-2050 3900);
FORCEPROP 0 LAST STATUS NOPOP
J 0
(-1925 3875);
DISPLAY 1.021277 (-1925 3875);
PAINT ORANGE (-1925 3875);
FORCEPROP 1 LAST VOLTAGE 50V
J 0
(-2000 3900);
DISPLAY 0.617021 (-2000 3900);
PAINT SKYBLUE (-2000 3900);
FORCEPROP 1 LAST PACK_TYPE 0402LF
J 0
(-2000 3700);
DISPLAY 0.617021 (-2000 3700);
PAINT SKYBLUE (-2000 3700);
FORCEPROP 1 LAST PART_NUMBER A36096-046
J 0
(-2000 3750);
DISPLAY 0.617021 (-2000 3750);
PAINT BLUE (-2000 3750);
FORCEPROP 1 LAST MATERIAL X7R
J 0
(-2000 3800);
DISPLAY 0.617021 (-2000 3800);
PAINT SKYBLUE (-2000 3800);
FORCEPROP 1 LAST TOLERANCE 10%
J 0
(-2000 3850);
DISPLAY 0.617021 (-2000 3850);
PAINT SKYBLUE (-2000 3850);
FORCEPROP 1 LAST VALUE 1000PF
J 0
(-2000 3950);
DISPLAY 0.617021 (-2000 3950);
PAINT SKYBLUE (-2000 3950);
FORCEPROP 1 LAST LOCATION CTI7
J 0
(-2175 3950);
DISPLAY 0.617021 (-2175 3950);
PAINT AQUA (-2175 3950);
FORCEPROP 0 LAST ROOM VDDQ_KLM_PWR_VR
J 0
(-2000 4100);
DISPLAY 1.021277 (-2000 4100);
PAINT ORANGE (-2000 4100);
DISPLAY INVISIBLE (-2000 4100);
FORCEPROP 1 LAST PATH I82
J 0
(-2000 4050);
DISPLAY 0.978723 (-2000 4050);
PAINT WHITE (-2000 4050);
DISPLAY INVISIBLE (-2000 4050);
FORCEPROP 2 LAST CDS_LIB mstr_discrete
J 0
(-2050 3900);
PAINT MONO (-2050 3900);
DISPLAY INVISIBLE (-2050 3900);
FORCEPROP 1 LASTPIN (-2050 3800) $PN 2
J 0
(-2040 3780);
DISPLAY 0.787234 (-2040 3780);
PAINT ORANGE (-2040 3780);
DISPLAY INVISIBLE (-2040 3780);
FORCEPROP 1 LASTPIN (-2050 4000) $PN 1
J 0
(-2040 3980);
DISPLAY 0.787234 (-2040 3980);
PAINT ORANGE (-2040 3980);
DISPLAY INVISIBLE (-2040 3980);
FORCEADD GND..1
(-2050 3700);
FORCEPROP 3 LASTPIN (-2050 3750) SIG_NAME GND\g
J 0
(-2040 3760);
DISPLAY 0.659574 (-2040 3760);
PAINT MONO (-2040 3760);
DISPLAY INVISIBLE (-2040 3760);
FORCEPROP 1 LAST HDL_POWER GND
J 0
(-2050 3850);
DISPLAY 1.170213 (-2050 3850);
PAINT GREEN (-2050 3850);
DISPLAY INVISIBLE (-2050 3850);
FORCEPROP 1 LAST BODY_TYPE PLUMBING
J 0
(-2095 3657);
DISPLAY 0.340426 (-2095 3657);
PAINT GREEN (-2095 3657);
DISPLAY INVISIBLE (-2095 3657);
FORCEPROP 1 LAST SIZE 1B
J 0
(-1975 3650);
DISPLAY 1.170213 (-1975 3650);
PAINT AQUA (-1975 3650);
DISPLAY INVISIBLE (-1975 3650);
FORCEPROP 1 LAST VOLTAGE 0
J 0
(-2050 3700);
PAINT SKYBLUE (-2050 3700);
DISPLAY INVISIBLE (-2050 3700);
FORCEPROP 2 LAST ROOM VDDQ_KLM_PWR_VR
J 0
(-2625 3775);
DISPLAY 1.361702 (-2625 3775);
PAINT ORANGE (-2625 3775);
DISPLAY INVISIBLE (-2625 3775);
FORCEPROP 1 LAST PATH I83
J 0
(-1975 3700);
DISPLAY 0.872340 (-1975 3700);
PAINT AQUA (-1975 3700);
DISPLAY INVISIBLE (-1975 3700);
FORCEPROP 2 LAST CDS_LIB mstr_symbols
J 0
(-2050 3700);
PAINT MONO (-2050 3700);
DISPLAY INVISIBLE (-2050 3700);
FORCEADD SC2K2P50V3KX-GP..1
(-2000 3500);
FORCEPROP 1 LAST LOCATION CT18
J 0
(-1975 3530);
DISPLAY 0.617021 (-1975 3530);
PAINT GREEN (-1975 3530);
FORCEPROP 0 LAST STATUS NOPOP
J 0
(-1950 3400);
DISPLAY 1.021277 (-1950 3400);
PAINT ORANGE (-1950 3400);
FORCEPROP 1 LAST VALUE SC2K2P50V3KX-GP
J 0
(-1975 3450);
DISPLAY 0.617021 (-1975 3450);
PAINT GREEN (-1975 3450);
FORCEPROP 2 LAST CDS_LIB w_hdl
J 0
(-2000 3500);
PAINT MONO (-2000 3500);
DISPLAY INVISIBLE (-2000 3500);
FORCEPROP 1 LAST PATH I84
J 0
(-2000 3500);
DISPLAY 0.617021 (-2000 3500);
PAINT GREEN (-2000 3500);
DISPLAY INVISIBLE (-2000 3500);
FORCEPROP 1 LAST CDS_LMAN_SYM_OUTLINE -50,25,50,-25
J 0
(-2000 3500);
DISPLAY 0.468085 (-2000 3500);
PAINT GREEN (-2000 3500);
DISPLAY INVISIBLE (-2000 3500);
FORCEPROP 1 LAST PACK_TYPE SMD-BCG6
J 0
(-2000 3500);
DISPLAY 0.617021 (-2000 3500);
PAINT GREEN (-2000 3500);
DISPLAY INVISIBLE (-2000 3500);
FORCEPROP 1 LAST PART_NUMBER 78.22224.2BL
J 0
(-2000 3500);
DISPLAY 0.617021 (-2000 3500);
PAINT GREEN (-2000 3500);
DISPLAY INVISIBLE (-2000 3500);
FORCEADD GND..1
(-2000 3000);
FORCEPROP 3 LASTPIN (-2000 3050) SIG_NAME GND\g
J 0
(-1990 3060);
DISPLAY 0.659574 (-1990 3060);
PAINT MONO (-1990 3060);
DISPLAY INVISIBLE (-1990 3060);
FORCEPROP 1 LAST HDL_POWER GND
J 0
(-2000 3150);
DISPLAY 1.723404 (-2000 3150);
PAINT GREEN (-2000 3150);
DISPLAY INVISIBLE (-2000 3150);
FORCEPROP 1 LAST BODY_TYPE PLUMBING
J 0
(-2045 2957);
DISPLAY 0.340426 (-2045 2957);
PAINT GREEN (-2045 2957);
DISPLAY INVISIBLE (-2045 2957);
FORCEPROP 1 LAST SIZE 1B
J 0
(-1925 2950);
DISPLAY 1.723404 (-1925 2950);
PAINT GREEN (-1925 2950);
DISPLAY INVISIBLE (-1925 2950);
FORCEPROP 1 LAST VOLTAGE 0
J 0
(-2000 3000);
PAINT SKYBLUE (-2000 3000);
DISPLAY INVISIBLE (-2000 3000);
FORCEPROP 2 LAST BOM_COST PROC_VRD_VCCIN_CPU0
J 0
(-2375 3075);
DISPLAY 1.446809 (-2375 3075);
PAINT MONO (-2375 3075);
DISPLAY INVISIBLE (-2375 3075);
FORCEPROP 2 LAST ROOM PVCCIN_CPU0_PWR_VR
J 0
(-2550 3075);
DISPLAY 1.936170 (-2550 3075);
PAINT ORANGE (-2550 3075);
DISPLAY INVISIBLE (-2550 3075);
FORCEPROP 1 LAST PATH I85
J 0
(-1925 3000);
DISPLAY 0.872340 (-1925 3000);
PAINT AQUA (-1925 3000);
DISPLAY INVISIBLE (-1925 3000);
FORCEPROP 2 LAST CDS_LIB mstr_symbols
J 0
(-2000 3000);
PAINT MONO (-2000 3000);
DISPLAY INVISIBLE (-2000 3000);
FORCEADD 3D01R5F-GP..1
R 4
(-2000 3200);
FORCEPROP 1 LAST VALUE 3D01R5F-GP
J 0
(-1950 3225);
DISPLAY 0.617021 (-1950 3225);
PAINT GREEN (-1950 3225);
FORCEPROP 0 LAST STATUS NOPOP
J 0
(-1950 3175);
DISPLAY 1.021277 (-1950 3175);
PAINT ORANGE (-1950 3175);
FORCEPROP 1 LAST LOCATION RT12
J 0
(-1950 3270);
DISPLAY 0.617021 (-1950 3270);
PAINT GREEN (-1950 3270);
FORCEPROP 2 LASTPIN (-2000 3325) SIG_NAME UN$208$3D01R5F-GP$I86$2
J 0
(-1990 3335);
DISPLAY 0.659574 (-1990 3335);
PAINT MONO (-1990 3335);
DISPLAY INVISIBLE (-1990 3335);
FORCEPROP 1 LAST PACK_TYPE SMD-RG5
R 2
J 0
(-2000 3200);
DISPLAY 0.617021 (-2000 3200);
PAINT GREEN (-2000 3200);
DISPLAY INVISIBLE (-2000 3200);
FORCEPROP 1 LAST PART_NUMBER 64.3R015.16L
R 2
J 0
(-2000 3200);
DISPLAY 0.617021 (-2000 3200);
PAINT GREEN (-2000 3200);
DISPLAY INVISIBLE (-2000 3200);
FORCEPROP 2 LAST CDS_LIB w_hdl
J 0
(-2000 3200);
PAINT MONO (-2000 3200);
DISPLAY INVISIBLE (-2000 3200);
FORCEPROP 1 LAST PATH I86
R 2
J 0
(-2000 3200);
DISPLAY 0.617021 (-2000 3200);
PAINT GREEN (-2000 3200);
DISPLAY INVISIBLE (-2000 3200);
FORCEPROP 1 LAST CDS_LMAN_SYM_OUTLINE -50,75,50,-75
R 2
J 0
(-2000 3200);
DISPLAY 0.468085 (-2000 3200);
PAINT GREEN (-2000 3200);
DISPLAY INVISIBLE (-2000 3200);
FORCEADD CAP_A..1
(-3850 775);
FORCEPROP 1 LAST TOLERANCE 10%
J 0
(-3800 725);
DISPLAY 0.617021 (-3800 725);
PAINT SKYBLUE (-3800 725);
FORCEPROP 1 LAST MATERIAL X7R
J 0
(-3800 675);
DISPLAY 0.617021 (-3800 675);
PAINT SKYBLUE (-3800 675);
FORCEPROP 1 LAST PART_NUMBER A36096-030
J 0
(-3800 625);
DISPLAY 0.617021 (-3800 625);
PAINT BLUE (-3800 625);
FORCEPROP 1 LAST PACK_TYPE 0402V
J 0
(-3800 575);
DISPLAY 0.617021 (-3800 575);
PAINT SKYBLUE (-3800 575);
FORCEPROP 1 LAST LOCATION CT21
J 0
(-3950 825);
DISPLAY 0.617021 (-3950 825);
PAINT AQUA (-3950 825);
FORCEPROP 1 LAST VALUE 0.1UF
J 0
(-3800 825);
DISPLAY 0.617021 (-3800 825);
PAINT SKYBLUE (-3800 825);
FORCEPROP 1 LAST VOLTAGE 16V
J 0
(-3800 775);
DISPLAY 0.617021 (-3800 775);
PAINT SKYBLUE (-3800 775);
FORCEPROP 0 LAST STATUS NOPOP
J 0
(-3775 525);
DISPLAY 1.021277 (-3775 525);
PAINT ORANGE (-3775 525);
FORCEPROP 2 LAST CDS_LIB dev_discrete
J 0
(-3850 775);
PAINT MONO (-3850 775);
DISPLAY INVISIBLE (-3850 775);
FORCEPROP 1 LAST PATH I87
J 0
(-3800 925);
DISPLAY 0.978723 (-3800 925);
PAINT WHITE (-3800 925);
DISPLAY INVISIBLE (-3800 925);
FORCEPROP 2 LAST ROOM PVCCIN_CPU0_PWR_VR
J 0
(-3800 925);
DISPLAY 1.361702 (-3800 925);
PAINT ORANGE (-3800 925);
DISPLAY INVISIBLE (-3800 925);
FORCEPROP 1 LASTPIN (-3850 875) $PN 1
J 0
(-3840 855);
DISPLAY 0.787234 (-3840 855);
PAINT ORANGE (-3840 855);
DISPLAY INVISIBLE (-3840 855);
FORCEPROP 1 LASTPIN (-3850 675) $PN 2
J 0
(-3840 655);
DISPLAY 0.787234 (-3840 655);
PAINT ORANGE (-3840 655);
DISPLAY INVISIBLE (-3840 655);
FORCEADD GND..1
(-3850 525);
FORCEPROP 3 LASTPIN (-3850 575) SIG_NAME GND\g
J 0
(-3840 585);
DISPLAY 0.659574 (-3840 585);
PAINT MONO (-3840 585);
DISPLAY INVISIBLE (-3840 585);
FORCEPROP 1 LAST HDL_POWER GND
J 0
(-3850 675);
DISPLAY 1.723404 (-3850 675);
PAINT GREEN (-3850 675);
DISPLAY INVISIBLE (-3850 675);
FORCEPROP 1 LAST BODY_TYPE PLUMBING
J 0
(-3895 482);
DISPLAY 0.340426 (-3895 482);
PAINT GREEN (-3895 482);
DISPLAY INVISIBLE (-3895 482);
FORCEPROP 2 LAST CDS_LIB mstr_symbols
J 0
(-3850 525);
PAINT MONO (-3850 525);
DISPLAY INVISIBLE (-3850 525);
FORCEPROP 1 LAST PATH I88
J 0
(-3775 525);
DISPLAY 0.872340 (-3775 525);
PAINT AQUA (-3775 525);
DISPLAY INVISIBLE (-3775 525);
FORCEPROP 1 LAST VOLTAGE 0
J 0
(-3850 525);
PAINT SKYBLUE (-3850 525);
DISPLAY INVISIBLE (-3850 525);
FORCEPROP 1 LAST SIZE 1B
J 0
(-3775 475);
DISPLAY 1.723404 (-3775 475);
PAINT GREEN (-3775 475);
DISPLAY INVISIBLE (-3775 475);
FORCEPROP 2 LAST BOM_COST PROC_VRD_VCCIN_CPU0
J 0
(-4225 600);
DISPLAY 1.446809 (-4225 600);
PAINT MONO (-4225 600);
DISPLAY INVISIBLE (-4225 600);
FORCEPROP 2 LAST ROOM PVCCIN_CPU0_PWR_VR
J 0
(-4400 600);
DISPLAY 1.936170 (-4400 600);
PAINT ORANGE (-4400 600);
DISPLAY INVISIBLE (-4400 600);
FORCEADD CAP_A..1
(-825 3425);
FORCEPROP 1 LAST PACK_TYPE 0603V
J 0
(-775 3225);
DISPLAY 0.617021 (-775 3225);
PAINT SKYBLUE (-775 3225);
FORCEPROP 1 LAST TOLERANCE 20%
J 0
(-775 3375);
DISPLAY 0.617021 (-775 3375);
PAINT SKYBLUE (-775 3375);
FORCEPROP 1 LAST LOCATION C1D14
J 0
(-775 3525);
DISPLAY 0.617021 (-775 3525);
PAINT AQUA (-775 3525);
FORCEPROP 1 LAST PART_NUMBER E15431-004
J 0
(-775 3275);
DISPLAY 0.617021 (-775 3275);
PAINT BLUE (-775 3275);
FORCEPROP 1 LAST VALUE 22.0UF
J 0
(-775 3475);
DISPLAY 0.617021 (-775 3475);
PAINT SKYBLUE (-775 3475);
FORCEPROP 1 LAST VOLTAGE 4V
J 0
(-775 3425);
DISPLAY 0.617021 (-775 3425);
PAINT SKYBLUE (-775 3425);
FORCEPROP 1 LAST MATERIAL X6S
J 0
(-775 3325);
DISPLAY 0.617021 (-775 3325);
PAINT SKYBLUE (-775 3325);
FORCEPROP 1 LASTPIN (-825 3525) $PN 1
J 0
(-815 3505);
DISPLAY 0.617021 (-815 3505);
PAINT GREEN (-815 3505);
FORCEPROP 1 LASTPIN (-825 3325) $PN 2
J 0
(-815 3305);
DISPLAY 0.617021 (-815 3305);
PAINT GREEN (-815 3305);
FORCEPROP 2 LAST SEC_TYPE 0603V
J 0
(-775 3625);
DISPLAY 1.936170 (-775 3625);
PAINT MONO (-775 3625);
DISPLAY INVISIBLE (-775 3625);
FORCEPROP 2 LAST SEC 1
J 0
(-775 3625);
DISPLAY 1.936170 (-775 3625);
PAINT MONO (-775 3625);
DISPLAY INVISIBLE (-775 3625);
FORCEPROP 2 LAST BOM_COST PROC_VRD_VCCIN_CPU0
J 0
(-775 3575);
DISPLAY 1.446809 (-775 3575);
PAINT MONO (-775 3575);
DISPLAY INVISIBLE (-775 3575);
FORCEPROP 2 LAST CDS_SEC 1
J 0
(-775 3575);
PAINT ORANGE (-775 3575);
DISPLAY INVISIBLE (-775 3575);
FORCEPROP 1 LAST PATH I9
J 0
(-775 3575);
DISPLAY 0.978723 (-775 3575);
PAINT WHITE (-775 3575);
DISPLAY INVISIBLE (-775 3575);
FORCEPROP 2 LAST ROOM PVCCIN_CPU1_PWR_VR
J 0
(-775 3575);
DISPLAY 1.446809 (-775 3575);
PAINT MONO (-775 3575);
DISPLAY INVISIBLE (-775 3575);
FORCEPROP 2 LAST CDS_LOCATION C1D14
J 0
(-775 3525);
DISPLAY 0.617021 (-775 3525);
PAINT AQUA (-775 3525);
DISPLAY INVISIBLE (-775 3525);
FORCEPROP 2 LAST CDS_LIB dev_discrete
J 0
(-825 3425);
PAINT ORANGE (-825 3425);
DISPLAY INVISIBLE (-825 3425);
FORCEADD CAP..1
(-2000 1300);
FORCEPROP 0 LAST STATUS NOPOP
J 0
(-1975 1400);
DISPLAY 1.021277 (-1975 1400);
PAINT ORANGE (-1975 1400);
FORCEPROP 1 LAST LOCATION CT19
J 0
(-2150 1300);
DISPLAY 0.617021 (-2150 1300);
PAINT AQUA (-2150 1300);
FORCEPROP 1 LAST PART_NUMBER A36096-046
J 0
(-1950 1150);
DISPLAY 0.617021 (-1950 1150);
PAINT BLUE (-1950 1150);
FORCEPROP 1 LAST TOLERANCE 10%
J 0
(-1950 1250);
DISPLAY 0.617021 (-1950 1250);
PAINT SKYBLUE (-1950 1250);
FORCEPROP 1 LAST VALUE 1000PF
J 0
(-1950 1350);
DISPLAY 0.617021 (-1950 1350);
PAINT SKYBLUE (-1950 1350);
FORCEPROP 1 LAST VOLTAGE 50V
J 0
(-1950 1300);
DISPLAY 0.617021 (-1950 1300);
PAINT SKYBLUE (-1950 1300);
FORCEPROP 1 LAST MATERIAL X7R
J 0
(-1950 1200);
DISPLAY 0.617021 (-1950 1200);
PAINT SKYBLUE (-1950 1200);
FORCEPROP 1 LAST PACK_TYPE 0402LF
J 0
(-1950 1100);
DISPLAY 0.617021 (-1950 1100);
PAINT SKYBLUE (-1950 1100);
FORCEPROP 2 LAST CDS_LIB mstr_discrete
J 0
(-2000 1300);
PAINT MONO (-2000 1300);
DISPLAY INVISIBLE (-2000 1300);
FORCEPROP 1 LAST PATH I90
J 0
(-1950 1450);
DISPLAY 0.978723 (-1950 1450);
PAINT WHITE (-1950 1450);
DISPLAY INVISIBLE (-1950 1450);
FORCEPROP 0 LAST ROOM VDDQ_KLM_PWR_VR
J 0
(-1950 1500);
DISPLAY 1.021277 (-1950 1500);
PAINT ORANGE (-1950 1500);
DISPLAY INVISIBLE (-1950 1500);
FORCEPROP 1 LASTPIN (-2000 1200) $PN 2
J 0
(-1990 1180);
DISPLAY 0.787234 (-1990 1180);
PAINT ORANGE (-1990 1180);
DISPLAY INVISIBLE (-1990 1180);
FORCEPROP 1 LASTPIN (-2000 1400) $PN 1
J 0
(-1990 1380);
DISPLAY 0.787234 (-1990 1380);
PAINT ORANGE (-1990 1380);
DISPLAY INVISIBLE (-1990 1380);
FORCEADD GND..1
(-2000 1100);
FORCEPROP 3 LASTPIN (-2000 1150) SIG_NAME GND\g
J 0
(-1990 1160);
DISPLAY 0.659574 (-1990 1160);
PAINT MONO (-1990 1160);
DISPLAY INVISIBLE (-1990 1160);
FORCEPROP 1 LAST HDL_POWER GND
J 0
(-2000 1250);
DISPLAY 1.170213 (-2000 1250);
PAINT GREEN (-2000 1250);
DISPLAY INVISIBLE (-2000 1250);
FORCEPROP 1 LAST BODY_TYPE PLUMBING
J 0
(-2045 1057);
DISPLAY 0.340426 (-2045 1057);
PAINT GREEN (-2045 1057);
DISPLAY INVISIBLE (-2045 1057);
FORCEPROP 2 LAST CDS_LIB mstr_symbols
J 0
(-2000 1100);
PAINT MONO (-2000 1100);
DISPLAY INVISIBLE (-2000 1100);
FORCEPROP 1 LAST PATH I91
J 0
(-1925 1100);
DISPLAY 0.872340 (-1925 1100);
PAINT AQUA (-1925 1100);
DISPLAY INVISIBLE (-1925 1100);
FORCEPROP 2 LAST ROOM VDDQ_KLM_PWR_VR
J 0
(-2575 1175);
DISPLAY 1.361702 (-2575 1175);
PAINT ORANGE (-2575 1175);
DISPLAY INVISIBLE (-2575 1175);
FORCEPROP 1 LAST VOLTAGE 0
J 0
(-2000 1100);
PAINT SKYBLUE (-2000 1100);
DISPLAY INVISIBLE (-2000 1100);
FORCEPROP 1 LAST SIZE 1B
J 0
(-1925 1050);
DISPLAY 1.170213 (-1925 1050);
PAINT AQUA (-1925 1050);
DISPLAY INVISIBLE (-1925 1050);
FORCEADD SC2K2P50V3KX-GP..1
(-1900 875);
FORCEPROP 0 LAST STATUS NOPOP
J 0
(-2175 850);
DISPLAY 1.021277 (-2175 850);
PAINT ORANGE (-2175 850);
FORCEPROP 1 LAST LOCATION CT20
J 0
(-1875 905);
DISPLAY 0.617021 (-1875 905);
PAINT GREEN (-1875 905);
FORCEPROP 1 LAST VALUE SC2K2P50V3KX-GP
J 0
(-1875 825);
DISPLAY 0.617021 (-1875 825);
PAINT GREEN (-1875 825);
FORCEPROP 2 LAST CDS_LIB w_hdl
J 0
(-1900 875);
PAINT MONO (-1900 875);
DISPLAY INVISIBLE (-1900 875);
FORCEPROP 1 LAST PATH I92
J 0
(-1900 875);
DISPLAY 0.617021 (-1900 875);
PAINT GREEN (-1900 875);
DISPLAY INVISIBLE (-1900 875);
FORCEPROP 1 LAST CDS_LMAN_SYM_OUTLINE -50,25,50,-25
J 0
(-1900 875);
DISPLAY 0.468085 (-1900 875);
PAINT GREEN (-1900 875);
DISPLAY INVISIBLE (-1900 875);
FORCEPROP 1 LAST PART_NUMBER 78.22224.2BL
J 0
(-1900 875);
DISPLAY 0.617021 (-1900 875);
PAINT GREEN (-1900 875);
DISPLAY INVISIBLE (-1900 875);
FORCEPROP 1 LAST PACK_TYPE SMD-BCG6
J 0
(-1900 875);
DISPLAY 0.617021 (-1900 875);
PAINT GREEN (-1900 875);
DISPLAY INVISIBLE (-1900 875);
FORCEADD GND..1
(-1900 400);
FORCEPROP 3 LASTPIN (-1900 450) SIG_NAME GND\g
J 0
(-1890 460);
DISPLAY 0.659574 (-1890 460);
PAINT MONO (-1890 460);
DISPLAY INVISIBLE (-1890 460);
FORCEPROP 1 LAST HDL_POWER GND
J 0
(-1900 550);
DISPLAY 1.723404 (-1900 550);
PAINT GREEN (-1900 550);
DISPLAY INVISIBLE (-1900 550);
FORCEPROP 1 LAST BODY_TYPE PLUMBING
J 0
(-1945 357);
DISPLAY 0.340426 (-1945 357);
PAINT GREEN (-1945 357);
DISPLAY INVISIBLE (-1945 357);
FORCEPROP 2 LAST CDS_LIB mstr_symbols
J 0
(-1900 400);
PAINT MONO (-1900 400);
DISPLAY INVISIBLE (-1900 400);
FORCEPROP 1 LAST PATH I93
J 0
(-1825 400);
DISPLAY 0.872340 (-1825 400);
PAINT AQUA (-1825 400);
DISPLAY INVISIBLE (-1825 400);
FORCEPROP 1 LAST SIZE 1B
J 0
(-1825 350);
DISPLAY 1.723404 (-1825 350);
PAINT GREEN (-1825 350);
DISPLAY INVISIBLE (-1825 350);
FORCEPROP 1 LAST VOLTAGE 0
J 0
(-1900 400);
PAINT SKYBLUE (-1900 400);
DISPLAY INVISIBLE (-1900 400);
FORCEPROP 2 LAST BOM_COST PROC_VRD_VCCIN_CPU0
J 0
(-2275 475);
DISPLAY 1.446809 (-2275 475);
PAINT MONO (-2275 475);
DISPLAY INVISIBLE (-2275 475);
FORCEPROP 2 LAST ROOM PVCCIN_CPU0_PWR_VR
J 0
(-2450 475);
DISPLAY 1.936170 (-2450 475);
PAINT ORANGE (-2450 475);
DISPLAY INVISIBLE (-2450 475);
FORCEADD 3D01R5F-GP..1
R 4
(-1900 650);
FORCEPROP 1 LAST VALUE 3D01R5F-GP
J 0
(-2175 600);
DISPLAY 0.617021 (-2175 600);
PAINT GREEN (-2175 600);
FORCEPROP 0 LAST STATUS NOPOP
J 0
(-2175 675);
DISPLAY 1.021277 (-2175 675);
PAINT ORANGE (-2175 675);
FORCEPROP 1 LAST LOCATION RT13
J 0
(-2025 645);
DISPLAY 0.617021 (-2025 645);
PAINT GREEN (-2025 645);
FORCEPROP 1 LAST CDS_LMAN_SYM_OUTLINE -50,75,50,-75
R 2
J 0
(-1900 650);
DISPLAY 0.468085 (-1900 650);
PAINT GREEN (-1900 650);
DISPLAY INVISIBLE (-1900 650);
FORCEPROP 1 LAST PATH I94
R 2
J 0
(-1900 650);
DISPLAY 0.617021 (-1900 650);
PAINT GREEN (-1900 650);
DISPLAY INVISIBLE (-1900 650);
FORCEPROP 2 LAST CDS_LIB w_hdl
J 0
(-1900 650);
PAINT MONO (-1900 650);
DISPLAY INVISIBLE (-1900 650);
FORCEPROP 1 LAST PART_NUMBER 64.3R015.16L
R 2
J 0
(-1900 650);
DISPLAY 0.617021 (-1900 650);
PAINT GREEN (-1900 650);
DISPLAY INVISIBLE (-1900 650);
FORCEPROP 1 LAST PACK_TYPE SMD-RG5
R 2
J 0
(-1900 650);
DISPLAY 0.617021 (-1900 650);
PAINT GREEN (-1900 650);
DISPLAY INVISIBLE (-1900 650);
FORCEPROP 2 LASTPIN (-1900 775) SIG_NAME UN$208$3D01R5F-GP$I94$2
J 0
(-1890 785);
DISPLAY 0.659574 (-1890 785);
PAINT MONO (-1890 785);
DISPLAY INVISIBLE (-1890 785);
FORCEADD RES..1
(-4975 3700);
FORCEPROP 1 LAST WATTAGE 1/16W
J 2
(-5000 3550);
DISPLAY 0.617021 (-5000 3550);
PAINT SKYBLUE (-5000 3550);
FORCEPROP 1 LAST LOCATION RT11
J 0
(-5200 3650);
DISPLAY 0.617021 (-5200 3650);
PAINT AQUA (-5200 3650);
FORCEPROP 1 LAST PART_NUMBER G21497-005
J 0
(-5075 3650);
DISPLAY 0.617021 (-5075 3650);
PAINT BLUE (-5075 3650);
FORCEPROP 1 LAST TOLERANCE 5%
J 0
(-4975 3600);
DISPLAY 0.617021 (-4975 3600);
PAINT SKYBLUE (-4975 3600);
FORCEPROP 1 LAST MATERIAL CHIP
J 0
(-4975 3550);
DISPLAY 0.617021 (-4975 3550);
PAINT SKYBLUE (-4975 3550);
FORCEPROP 1 LAST PACK_TYPE 0402
J 0
(-4875 3550);
DISPLAY 0.617021 (-4875 3550);
PAINT SKYBLUE (-4875 3550);
FORCEPROP 1 LAST VALUE 0.0
J 2
(-5000 3600);
DISPLAY 0.617021 (-5000 3600);
PAINT SKYBLUE (-5000 3600);
FORCEPROP 2 LAST BOM_COST DEBUG
J 0
(-5025 3900);
DISPLAY 1.021277 (-5025 3900);
PAINT ORANGE (-5025 3900);
DISPLAY INVISIBLE (-5025 3900);
FORCEPROP 2 LAST ROOM BMC_DEBUG_HEADER
J 0
(-5025 3850);
DISPLAY 1.021277 (-5025 3850);
PAINT ORANGE (-5025 3850);
DISPLAY INVISIBLE (-5025 3850);
FORCEPROP 1 LAST PATH I96
J 0
(-5025 3850);
DISPLAY 0.978723 (-5025 3850);
PAINT WHITE (-5025 3850);
DISPLAY INVISIBLE (-5025 3850);
FORCEPROP 2 LAST CDS_LIB mstr_discrete
J 0
(-4975 3700);
PAINT MONO (-4975 3700);
DISPLAY INVISIBLE (-4975 3700);
FORCEPROP 1 LASTPIN (-5075 3700) $PN 1
J 0
(-5063 3712);
DISPLAY 0.787234 (-5063 3712);
PAINT ORANGE (-5063 3712);
DISPLAY INVISIBLE (-5063 3712);
FORCEPROP 1 LASTPIN (-4875 3700) $PN 2
J 0
(-4913 3712);
DISPLAY 0.787234 (-4913 3712);
PAINT ORANGE (-4913 3712);
DISPLAY INVISIBLE (-4913 3712);
FORCEADD RES..1
(-4925 1075);
FORCEPROP 1 LAST PACK_TYPE 0402
J 0
(-4825 925);
DISPLAY 0.617021 (-4825 925);
PAINT SKYBLUE (-4825 925);
FORCEPROP 1 LAST MATERIAL CHIP
J 0
(-4925 925);
DISPLAY 0.617021 (-4925 925);
PAINT SKYBLUE (-4925 925);
FORCEPROP 1 LAST TOLERANCE 5%
J 0
(-4925 975);
DISPLAY 0.617021 (-4925 975);
PAINT SKYBLUE (-4925 975);
FORCEPROP 1 LAST PART_NUMBER G21497-005
J 0
(-5025 1025);
DISPLAY 0.617021 (-5025 1025);
PAINT BLUE (-5025 1025);
FORCEPROP 1 LAST LOCATION RT14
J 0
(-4975 1100);
DISPLAY 0.617021 (-4975 1100);
PAINT AQUA (-4975 1100);
FORCEPROP 1 LAST VALUE 0.0
J 2
(-4950 975);
DISPLAY 0.617021 (-4950 975);
PAINT SKYBLUE (-4950 975);
FORCEPROP 1 LAST WATTAGE 1/16W
J 2
(-4950 925);
DISPLAY 0.617021 (-4950 925);
PAINT SKYBLUE (-4950 925);
FORCEPROP 2 LAST BOM_COST DEBUG
J 0
(-4975 1275);
DISPLAY 1.021277 (-4975 1275);
PAINT ORANGE (-4975 1275);
DISPLAY INVISIBLE (-4975 1275);
FORCEPROP 2 LAST ROOM BMC_DEBUG_HEADER
J 0
(-4975 1225);
DISPLAY 1.021277 (-4975 1225);
PAINT ORANGE (-4975 1225);
DISPLAY INVISIBLE (-4975 1225);
FORCEPROP 1 LAST PATH I97
J 0
(-4975 1225);
DISPLAY 0.978723 (-4975 1225);
PAINT WHITE (-4975 1225);
DISPLAY INVISIBLE (-4975 1225);
FORCEPROP 2 LAST CDS_LIB mstr_discrete
J 0
(-4925 1075);
PAINT MONO (-4925 1075);
DISPLAY INVISIBLE (-4925 1075);
FORCEPROP 1 LASTPIN (-5025 1075) $PN 1
J 0
(-5013 1087);
DISPLAY 0.787234 (-5013 1087);
PAINT ORANGE (-5013 1087);
DISPLAY INVISIBLE (-5013 1087);
FORCEPROP 1 LASTPIN (-4825 1075) $PN 2
J 0
(-4863 1087);
DISPLAY 0.787234 (-4863 1087);
PAINT ORANGE (-4863 1087);
DISPLAY INVISIBLE (-4863 1087);
FORCEADD DNS..2
(-620 1445);
PAINT RED (-620 1445);
FORCEPROP 1 LAST COMMENT_BODY TRUE
R 1
J 0
(-545 1220);
DISPLAY 0.872340 (-545 1220);
PAINT GREEN (-545 1220);
DISPLAY INVISIBLE (-545 1220);
FORCEPROP 2 LAST CDS_LIB mstr_misc
J 0
(-620 1445);
PAINT ORANGE (-620 1445);
DISPLAY INVISIBLE (-620 1445);
FORCEADD DNS..2
(-695 4070);
PAINT RED (-695 4070);
FORCEPROP 1 LAST COMMENT_BODY TRUE
R 1
J 0
(-620 3845);
DISPLAY 0.872340 (-620 3845);
PAINT GREEN (-620 3845);
DISPLAY INVISIBLE (-620 3845);
FORCEPROP 2 LAST CDS_LIB mstr_misc
J 0
(-695 4070);
PAINT ORANGE (-695 4070);
DISPLAY INVISIBLE (-695 4070);
FORCEADD INTEL_CORP_BPAGE..1
(0 0);
FORCEPROP 1 LAST CDS_CON_LAST_MODIFIED Tue Dec 01 11:52:23 2015
J 0
(-1425 325);
PAINT ORANGE (-1425 325);
DISPLAY INVISIBLE (-1425 325);
FORCEPROP 1 LAST CUSTOM_TXT_CDS <CURRENT_DESIGN_SHEET> OF <TOTAL_DESIGN_SHEETS>
J 0
(-500 25);
PAINT GREEN (-500 25);
FORCEPROP 2 LAST CUSTOM_TXT_CDS <XR_PAGE_TITLE>
J 0
(-7890 5250);
DISPLAY 0.638298 (-7890 5250);
PAINT PINK (-7890 5250);
DISPLAY INVISIBLE (-7890 5250);
FORCEPROP 2 LAST CUSTOM_TXT_CDS <CON_LAST_MODIFIED>
J 0
(-1700 300);
PAINT ORANGE (-1700 300);
FORCEPROP 1 LAST SCH_DEPT BESD
J 1
(-4450 100);
DISPLAY 1.212766 (-4450 100);
PAINT YELLOW (-4450 100);
FORCEPROP 1 LAST SCH_NUMBER H4694802
J 0
(-1300 150);
DISPLAY 1.212766 (-1300 150);
PAINT YELLOW (-1300 150);
FORCEPROP 1 LAST SCH_TITLE VCCIN CPU1 (3 OF 4)
J 0
(-7950 50);
DISPLAY 1.212766 (-7950 50);
PAINT ORANGE (-7950 50);
FORCEPROP 1 LAST SCH_REV 2.420
J 0
(-250 150);
DISPLAY 0.978723 (-250 150);
PAINT YELLOW (-250 150);
FORCEPROP 1 LAST SCH_ADDRESS3 Santa Clara, CA 95052-8119
J 0
(-3975 25);
DISPLAY 0.617021 (-3975 25);
PAINT GREEN (-3975 25);
FORCEPROP 1 LAST SCH_ADDRESS2 P.O. BOX 58119
J 0
(-3975 75);
DISPLAY 0.617021 (-3975 75);
PAINT GREEN (-3975 75);
FORCEPROP 1 LAST SCH_ADDRESS1 2200 Mission College Blvd.
J 0
(-3975 125);
DISPLAY 0.617021 (-3975 125);
PAINT GREEN (-3975 125);
FORCEPROP 1 LAST COMMENT_BODY TRUE
J 0
(12 12);
DISPLAY 0.468085 (12 12);
PAINT GREEN (12 12);
DISPLAY INVISIBLE (12 12);
FORCEPROP 2 LAST CDS_LIB mstr_symbols
J 0
(0 0);
PAINT MONO (0 0);
DISPLAY INVISIBLE (0 0);
FORCEPROP 2 LAST PAGE_BORDER TRUE
J 0
(-7890 5250);
DISPLAY 0.638298 (-7890 5250);
PAINT PINK (-7890 5250);
DISPLAY INVISIBLE (-7890 5250);
FORCEPROP 2 LAST CDS_XR_PAGE_TITLE CR-208 : @BASEBOARD_FAB2_LIB.BASEBOARD_FAB2(SCH_1):PAGE208
J 0
(-7890 5250);
DISPLAY 0.638298 (-7890 5250);
PAINT PINK (-7890 5250);
DISPLAY INVISIBLE (-7890 5250);
WIRE 16 -1 (-825 3325)(-825 3225);
WIRE 16 -1 (-400 3225)(-825 3225);
WIRE 16 -1 (-400 3300)(-400 3225);
WIRE 16 -1 (-400 3100)(-400 3225);
WIRE 16 -1 (-4150 2525)(-4150 2375);
WIRE 16 -1 (-3725 2375)(-4150 2375);
WIRE 16 -1 (-3725 2525)(-3725 2375);
WIRE 16 -1 (-3275 2375)(-3725 2375);
WIRE 16 -1 (-3275 2525)(-3275 2375);
WIRE 16 -1 (-2825 2375)(-3275 2375);
WIRE 16 -1 (-2825 2525)(-2825 2375);
WIRE 16 -1 (-2375 2375)(-2825 2375);
WIRE 16 -1 (-2375 2500)(-2375 2375);
WIRE 16 -1 (-1925 2375)(-2375 2375);
WIRE 16 -1 (-1925 2525)(-1925 2375);
WIRE 16 -1 (-1925 2375)(-1450 2375);
WIRE 16 -1 (-1450 2525)(-1450 2375);
WIRE 16 -1 (-1000 2375)(-1450 2375);
WIRE 16 -1 (-1000 2475)(-1000 2375);
WIRE 16 -1 (-1000 2375)(-1000 2325);
WIRE 16 -1 (-3750 1425)(-3975 1425);
WIRE 16 -1 (-3975 1425)(-3975 375);
WIRE 16 -1 (-3975 375)(-850 375);
WIRE 16 -1 (-850 375)(-850 1025);
WIRE 16 -1 (-1225 1025)(-850 1025);
WIRE 16 -1 (-850 1025)(-700 1025);
WIRE 16 -1 (-700 900)(-700 1025);
WIRE 16 -1 (-350 1025)(-700 1025);
WIRE 16 -1 (-350 900)(-350 1025);
WIRE 16 -1 (-350 1075)(-350 1025);
WIRE 16 -1 (-700 700)(-700 550);
WIRE 16 -1 (-350 550)(-700 550);
WIRE 16 -1 (-350 700)(-350 550);
WIRE 16 -1 (-350 500)(-350 550);
WIRE 16 -1 (-2800 3475)(-2600 3475);
WIRE 16 -1 (-2600 3425)(-2600 3475);
WIRE 16 -1 (-2600 3375)(-2600 3425);
WIRE 16 -1 (-2600 3425)(-2800 3425);
WIRE 16 -1 (-2600 3375)(-2800 3375);
WIRE 16 -1 (-2600 3325)(-2600 3375);
WIRE 16 -1 (-2600 3225)(-2600 3325);
WIRE 16 -1 (-2600 3325)(-2800 3325);
WIRE 16 -1 (-1000 2675)(-1000 2800);
WIRE 16 -1 (-1000 2800)(-1450 2800);
WIRE 16 -1 (-1450 2725)(-1450 2800);
WIRE 16 -1 (-1925 2800)(-1450 2800);
WIRE 16 -1 (-1925 2725)(-1925 2800);
WIRE 16 -1 (-1925 2800)(-2375 2800);
WIRE 16 -1 (-2375 2700)(-2375 2800);
WIRE 16 -1 (-2375 2800)(-2825 2800);
WIRE 16 -1 (-2825 2725)(-2825 2800);
WIRE 16 -1 (-2825 2800)(-3275 2800);
WIRE 16 -1 (-3275 2725)(-3275 2800);
WIRE 16 -1 (-3275 2800)(-3725 2800);
WIRE 16 -1 (-3725 2725)(-3725 2800);
WIRE 16 -1 (-3725 2800)(-4150 2800);
WIRE 16 -1 (-4150 2800)(-4150 2725);
WIRE 16 -1 (-4250 2800)(-4150 2800);
WIRE 16 -1 (-4250 2800)(-4250 2850);
WIRE 16 -1 (-2750 875)(-2575 875);
WIRE 16 -1 (-2575 875)(-2575 825);
WIRE 16 -1 (-2750 825)(-2575 825);
WIRE 16 -1 (-2575 825)(-2575 775);
WIRE 16 -1 (-2750 775)(-2575 775);
WIRE 16 -1 (-2575 775)(-2575 725);
WIRE 16 -1 (-2575 650)(-2575 725);
WIRE 16 -1 (-2575 725)(-2750 725);
WIRE 16 -1 (-3800 4325)(-4375 4325);
WIRE 16 -1 (-4375 4375)(-4375 4325);
WIRE 16 -1 (-3800 4375)(-4375 4375);
WIRE 16 -1 (-4375 4375)(-5875 4375);
WIRE 16 -1 (-5875 4250)(-5875 4375);
WIRE 16 -1 (-6250 4375)(-5875 4375);
WIRE 16 -1 (-6250 4250)(-6250 4375);
WIRE 16 -1 (-6625 4375)(-6250 4375);
WIRE 16 -1 (-6625 4250)(-6625 4375);
WIRE 16 -1 (-7000 4375)(-6625 4375);
WIRE 16 -1 (-7000 4250)(-7000 4375);
WIRE 16 -1 (-7000 4375)(-7375 4375);
WIRE 16 -1 (-7375 4250)(-7375 4375);
WIRE 16 -1 (-7425 4375)(-7375 4375);
WIRE 16 -1 (-7425 4475)(-7425 4375);
WIRE 16 -1 (-4850 4100)(-4850 3900);
WIRE 16 -1 (-4850 3900)(-5000 3900);
WIRE 16 -1 (-5000 4100)(-5000 3900);
WIRE 16 -1 (-5000 3900)(-5575 3900);
WIRE 16 -1 (-5575 4050)(-5575 3900);
WIRE 16 -1 (-5575 3900)(-5875 3900);
WIRE 16 -1 (-5875 4050)(-5875 3900);
WIRE 16 -1 (-6250 3900)(-5875 3900);
WIRE 16 -1 (-6250 4050)(-6250 3900);
WIRE 16 -1 (-6625 3900)(-6250 3900);
WIRE 16 -1 (-6625 4050)(-6625 3900);
WIRE 16 -1 (-7000 3900)(-6625 3900);
WIRE 16 -1 (-7000 4050)(-7000 3900);
WIRE 16 -1 (-7000 3900)(-7375 3900);
WIRE 16 -1 (-7375 4050)(-7375 3900);
WIRE 16 -1 (-7425 3900)(-7375 3900);
WIRE 16 -1 (-7425 3825)(-7425 3900);
WIRE 16 -1 (-4075 1725)(-3750 1725);
WIRE 16 -1 (-4075 1775)(-4075 1725);
WIRE 16 -1 (-3750 1775)(-4075 1775);
WIRE 16 -1 (-6025 1775)(-4075 1775);
WIRE 16 -1 (-6025 1550)(-6025 1775);
WIRE 16 -1 (-6025 1775)(-6350 1775);
WIRE 16 -1 (-6350 1600)(-6350 1775);
WIRE 16 -1 (-6350 1775)(-6725 1775);
WIRE 16 -1 (-6725 1575)(-6725 1775);
WIRE 16 -1 (-6725 1775)(-7075 1775);
WIRE 16 -1 (-7075 1575)(-7075 1775);
WIRE 16 -1 (-7075 1775)(-7375 1775);
WIRE 16 -1 (-7375 1600)(-7375 1775);
WIRE 16 -1 (-7375 1900)(-7375 1775);
WIRE 16 -1 (-4900 1475)(-4900 1250);
WIRE 16 -1 (-4900 1250)(-5075 1250);
WIRE 16 -1 (-5075 1475)(-5075 1250);
WIRE 16 -1 (-5075 1250)(-5700 1250);
WIRE 16 -1 (-5700 1475)(-5700 1250);
WIRE 16 -1 (-5700 1250)(-6025 1250);
WIRE 16 -1 (-6025 1350)(-6025 1250);
WIRE 16 -1 (-6025 1250)(-6350 1250);
WIRE 16 -1 (-6350 1400)(-6350 1250);
WIRE 16 -1 (-6350 1250)(-6725 1250);
WIRE 16 -1 (-6725 1375)(-6725 1250);
WIRE 16 -1 (-6725 1250)(-7075 1250);
WIRE 16 -1 (-7075 1375)(-7075 1250);
WIRE 16 -1 (-7075 1250)(-7375 1250);
WIRE 16 -1 (-7375 1400)(-7375 1250);
WIRE 16 -1 (-7375 1000)(-7375 1250);
WIRE 16 -1 (-4175 4125)(-3800 4125);
WIRE 16 -1 (-4175 4225)(-4175 4125);
WIRE 16 -1 (-3800 4225)(-4175 4225);
WIRE 16 -1 (-4175 4225)(-4175 4700);
WIRE 16 -1 (-4175 4700)(-4850 4700);
WIRE 16 -1 (-4850 4300)(-4850 4700);
WIRE 16 -1 (-4850 4700)(-4925 4700);
WIRE 16 -1 (-4925 4700)(-5000 4700);
WIRE 16 -1 (-4925 4800)(-4925 4700);
WIRE 16 -1 (-5000 4300)(-5000 4700);
WIRE 16 -1 (-5000 4700)(-5175 4700);
WIRE 16 -1 (-3950 1625)(-3950 1525);
WIRE 16 -1 (-3950 1625)(-3750 1625);
WIRE 16 -1 (-3950 2025)(-3950 1625);
WIRE 16 -1 (-3950 1525)(-3750 1525);
WIRE 16 -1 (-3950 2025)(-4900 2025);
WIRE 16 -1 (-4900 1675)(-4900 2025);
WIRE 16 -1 (-5000 2025)(-4900 2025);
WIRE 16 -1 (-5075 2025)(-5000 2025);
WIRE 16 -1 (-5000 2025)(-5000 2100);
WIRE 16 -1 (-5075 1675)(-5075 2025);
WIRE 16 -1 (-5075 2025)(-5350 2025);
WIRE 16 -1 (-700 3975)(-700 3875);
WIRE 16 -1 (-625 1350)(-625 1275);
WIRE 16 -1 (-3975 3275)(-3975 3175);
WIRE 16 -1 (-3800 4025)(-4050 4025);
WIRE 16 -1 (-4050 4025)(-4050 2950);
WIRE 16 -1 (-4050 2950)(-1175 2950);
WIRE 16 -1 (-1175 2950)(-1175 3625);
WIRE 16 -1 (-1375 3625)(-1175 3625);
WIRE 16 -1 (-825 3625)(-1175 3625);
WIRE 16 -1 (-825 3525)(-825 3625);
WIRE 16 -1 (-400 3625)(-825 3625);
WIRE 16 -1 (-400 3500)(-400 3625);
WIRE 16 -1 (-400 3625)(-400 3650);
WIRE 16 -1 (-2050 3800)(-2050 3750);
WIRE 16 -1 (-2000 3075)(-2000 3050);
WIRE 16 -1 (-3850 675)(-3850 575);
WIRE 16 -1 (-2000 1200)(-2000 1150);
WIRE 16 -1 (-1900 525)(-1900 450);
WIRE 3 2175 (-2175 1050)(-1750 1050);
WIRE 3 2175 (-2175 1050)(-2175 350);
WIRE 3 2175 (-1750 1050)(-1750 350);
WIRE 3 2175 (-2175 350)(-1750 350);
WIRE 3 2175 (-4150 450)(-3375 450);
WIRE 3 2175 (-4150 1025)(-4150 450);
WIRE 3 2175 (-3375 1025)(-3375 450);
WIRE 3 2175 (-4150 1025)(-3375 1025);
WIRE 3 2175 (-2200 2975)(-1650 2975);
WIRE 3 2175 (-2200 3650)(-2200 2975);
WIRE 3 2175 (-1650 3650)(-1650 2975);
WIRE 3 2175 (-2200 3650)(-1650 3650);
WIRE 16 -1 (-2800 4050)(-2050 4050);
FORCEPROP 2 LAST SIG_NAME A_TSENSE_PVCCIN_CPU1
J 0
(-2705 4060);
DISPLAY 0.617021 (-2705 4060);
PAINT ORANGE (-2705 4060);
WIRE 16 -1 (-2800 4050)(-2800 3925);
WIRE 16 -1 (-2050 4050)(-1575 4050);
WIRE 16 -1 (-2050 4000)(-2050 4050);
WIRE 3 2175 (-2200 4100)(-1700 4100);
WIRE 3 2175 (-2200 4100)(-2200 3675);
WIRE 3 2175 (-1700 4100)(-1700 3675);
WIRE 3 2175 (-2200 3675)(-1700 3675);
WIRE 16 -1 (-2800 3625)(-2000 3625);
FORCEPROP 0 LAST VOLTAGE 5
J 0
(-2350 3700);
DISPLAY 1.021277 (-2350 3700);
PAINT SKYBLUE (-2350 3700);
DISPLAY INVISIBLE (-2350 3700);
FORCEPROP 2 LAST SIG_NAME VR_PVCCIN_CPU1_PHASE3
J 0
(-2715 3635);
DISPLAY 0.617021 (-2715 3635);
PAINT ORANGE (-2715 3635);
FORCEPROP 2 LASTPROP $XRERR UNIQUE?
J 0
(-2955 3635);
DISPLAY 0.638298 (-2955 3635);
PAINT MONO (-2955 3635);
DISPLAY INVISIBLE (-2955 3635);
WIRE 16 -1 (-2800 3625)(-2800 3575);
WIRE 16 -1 (-2000 3625)(-1575 3625);
WIRE 16 -1 (-2000 3575)(-2000 3625);
WIRE 16 2175 (-6275 3350)(-5350 3350);
WIRE 16 2175 (-6275 3750)(-6275 3350);
WIRE 16 2175 (-5350 3750)(-5350 3350);
WIRE 16 2175 (-6275 3750)(-5350 3750);
WIRE 16 -1 (-5975 750)(-4075 750);
FORCEPROP 0 LAST VOLTAGE 5
J 0
(-5850 825);
DISPLAY 1.021277 (-5850 825);
PAINT SKYBLUE (-5850 825);
DISPLAY INVISIBLE (-5850 825);
FORCEPROP 2 LAST SIG_NAME VR_PVCCIN_CPU1_PH4_PHASE
J 0
(-5940 760);
DISPLAY 0.617021 (-5940 760);
PAINT ORANGE (-5940 760);
FORCEPROP 2 LASTPROP $XRERR UNIQUE?
J 0
(-6180 760);
DISPLAY 0.638298 (-6180 760);
PAINT MONO (-6180 760);
DISPLAY INVISIBLE (-6180 760);
WIRE 16 -1 (-5975 750)(-5975 800);
WIRE 16 -1 (-4075 750)(-4075 925);
WIRE 16 -1 (-4075 925)(-3750 925);
WIRE 16 -1 (-2750 1625)(-625 1625);
FORCEPROP 0 LAST SIG_NAME VR_PVCCIN_CPU1_PH4_OCSET
J 0
(-2610 1635);
DISPLAY 0.617021 (-2610 1635);
PAINT ORANGE (-2610 1635);
FORCEPROP 2 LASTPROP $XRERR UNIQUE?
J 0
(-2850 1635);
DISPLAY 0.638298 (-2850 1635);
PAINT MONO (-2850 1635);
DISPLAY INVISIBLE (-2850 1635);
WIRE 16 -1 (-625 1625)(-625 1550);
WIRE 16 -1 (-2750 1825)(-875 1825);
FORCEPROP 2 LAST SIG_NAME ISENSE_PVCCIN_CPU1_PH4_IMON
J 0
(-1905 1841);
DISPLAY 0.617021 (-1905 1841);
PAINT ORANGE (-1905 1841);
WIRE 3 2175 (-2175 1475)(-1750 1475);
WIRE 3 2175 (-2175 1475)(-2175 1075);
WIRE 3 2175 (-1750 1475)(-1750 1075);
WIRE 3 2175 (-2175 1075)(-1750 1075);
WIRE 16 -1 (-3750 1825)(-5700 1825);
FORCEPROP 0 LAST VOLTAGE 5
J 0
(-4375 1900);
DISPLAY 1.021277 (-4375 1900);
PAINT SKYBLUE (-4375 1900);
DISPLAY INVISIBLE (-4375 1900);
FORCEPROP 2 LAST SIG_NAME VR_PVCCIN_CPU1_PH4_VCIN
J 0
(-4765 1835);
DISPLAY 0.617021 (-4765 1835);
PAINT ORANGE (-4765 1835);
FORCEPROP 2 LASTPROP $XRERR UNIQUE?
J 0
(-5005 1835);
DISPLAY 0.638298 (-5005 1835);
PAINT MONO (-5005 1835);
DISPLAY INVISIBLE (-5005 1835);
WIRE 16 -1 (-5700 2025)(-5700 1825);
WIRE 16 -1 (-5700 1675)(-5700 1825);
WIRE 16 -1 (-5700 2025)(-5550 2025);
WIRE 3 2175 (-5200 900)(-4725 900);
WIRE 3 2175 (-5200 1150)(-5200 900);
WIRE 3 2175 (-4725 1150)(-4725 900);
WIRE 3 2175 (-5200 1150)(-4725 1150);
WIRE 16 -1 (-2750 1025)(-1900 1025);
FORCEPROP 0 LAST VOLTAGE 5
J 0
(-2075 1100);
DISPLAY 1.021277 (-2075 1100);
PAINT SKYBLUE (-2075 1100);
DISPLAY INVISIBLE (-2075 1100);
FORCEPROP 2 LAST SIG_NAME VR_PVCCIN_CPU1_PHASE4
J 0
(-2715 1035);
DISPLAY 0.617021 (-2715 1035);
PAINT ORANGE (-2715 1035);
FORCEPROP 2 LASTPROP $XRERR UNIQUE?
J 0
(-2955 1035);
DISPLAY 0.638298 (-2955 1035);
PAINT MONO (-2955 1035);
DISPLAY INVISIBLE (-2955 1035);
WIRE 16 -1 (-2750 1025)(-2750 975);
WIRE 16 -1 (-1900 1025)(-1425 1025);
WIRE 16 -1 (-1900 950)(-1900 1025);
WIRE 3 2175 (-4275 3625)(-3700 3625);
WIRE 3 2175 (-4275 3625)(-4275 3075);
WIRE 3 2175 (-3700 3625)(-3700 3075);
WIRE 3 2175 (-4275 3075)(-3700 3075);
WIRE 16 -1 (-3750 1325)(-4525 1325);
FORCEPROP 0 LAST SIG_NAME TP_PVCCIN_CPU1_PH4_GL_1
J 0
(-4510 1335);
DISPLAY 0.617021 (-4510 1335);
PAINT ORANGE (-4510 1335);
FORCEPROP 2 LASTPROP $XRERR UNIQUE?
J 0
(-4765 1325);
DISPLAY 0.638298 (-4765 1325);
PAINT MONO (-4765 1325);
DISPLAY INVISIBLE (-4765 1325);
WIRE 16 -1 (-2750 1450)(-2000 1450);
FORCEPROP 2 LAST SIG_NAME A_TSENSE_PVCCIN_CPU1
J 0
(-2684 1463);
DISPLAY 0.617021 (-2684 1463);
PAINT ORANGE (-2684 1463);
WIRE 16 -1 (-2750 1450)(-2750 1325);
WIRE 16 -1 (-2000 1450)(-1725 1450);
WIRE 16 -1 (-2000 1400)(-2000 1450);
WIRE 16 -1 (-1900 775)(-1900 800);
WIRE 16 -1 (-2000 3425)(-2000 3325);
WIRE 16 -1 (-900 2125)(-3850 2125);
FORCEPROP 2 LAST SIG_NAME VR_PVCCIN_CPU1_AIREF4
J 2
(-1387 2160);
DISPLAY 0.617021 (-1387 2160);
PAINT ORANGE (-1387 2160);
WIRE 16 -1 (-3850 1075)(-3850 2125);
WIRE 16 -1 (-3750 1075)(-3850 1075);
WIRE 16 -1 (-3850 875)(-3850 1075);
WIRE 16 -1 (-2800 4175)(-2050 4175);
FORCEPROP 0 LAST SIG_NAME NC_PVCCIN_CPU1_PH3_P31
J 0
(-2660 4185);
DISPLAY 0.617021 (-2660 4185);
PAINT ORANGE (-2660 4185);
FORCEPROP 2 LASTPROP $XRERR UNIQUE?
J 0
(-2020 4175);
DISPLAY 0.638298 (-2020 4175);
PAINT MONO (-2020 4175);
DISPLAY INVISIBLE (-2020 4175);
WIRE 16 2175 (-6325 625)(-5350 625);
WIRE 16 2175 (-6325 1150)(-6325 625);
WIRE 16 2175 (-5350 1150)(-5350 625);
WIRE 16 2175 (-6325 1150)(-5350 1150);
WIRE 16 -1 (-5025 1075)(-5975 1075);
FORCEPROP 2 LAST SIG_NAME VR_PVCCIN_CPU1_PH4_BOOT
J 0
(-5940 1085);
DISPLAY 0.617021 (-5940 1085);
PAINT ORANGE (-5940 1085);
FORCEPROP 2 LASTPROP $XRERR UNIQUE?
J 0
(-6180 1085);
DISPLAY 0.638298 (-6180 1085);
PAINT MONO (-6180 1085);
DISPLAY INVISIBLE (-6180 1085);
WIRE 16 -1 (-5975 1000)(-5975 1075);
WIRE 16 -1 (-4075 1075)(-4075 975);
WIRE 16 -1 (-4825 1075)(-4075 1075);
FORCEPROP 2 LAST SIG_NAME VR_PVCCIN_CPU1_PH4_BOOT_R
J 0
(-4715 1085);
DISPLAY 0.617021 (-4715 1085);
PAINT ORANGE (-4715 1085);
FORCEPROP 2 LASTPROP $XRERR UNIQUE?
J 0
(-4955 1085);
DISPLAY 0.638298 (-4955 1085);
PAINT MONO (-4955 1085);
DISPLAY INVISIBLE (-4955 1085);
WIRE 16 -1 (-4075 975)(-3750 975);
WIRE 16 -1 (-6825 1175)(-3750 1175);
FORCEPROP 2 LAST SIG_NAME VR_PVCCIN_CPU1_PWM4
J 0
(-6838 1185);
DISPLAY 0.617021 (-6838 1185);
PAINT ORANGE (-6838 1185);
WIRE 16 -1 (-4525 1275)(-3750 1275);
FORCEPROP 0 LAST SIG_NAME TP_PVCCIN_CPU1_PH4_GL_0
J 0
(-4510 1285);
DISPLAY 0.617021 (-4510 1285);
PAINT ORANGE (-4510 1285);
FORCEPROP 2 LASTPROP $XRERR UNIQUE?
J 0
(-4765 1275);
DISPLAY 0.638298 (-4765 1275);
PAINT MONO (-4765 1275);
DISPLAY INVISIBLE (-4765 1275);
WIRE 16 -1 (-6825 3775)(-3800 3775);
WIRE 16 -1 (-5975 3700)(-5075 3700);
WIRE 16 -1 (-5975 3675)(-5975 3700);
FORCEPROP 2 LAST SIG_NAME VR_PVCCIN_CPU1_PH3_BOOT
J 0
(-5990 3710);
DISPLAY 0.617021 (-5990 3710);
PAINT ORANGE (-5990 3710);
FORCEPROP 2 LASTPROP $XRERR UNIQUE?
J 0
(-6230 3710);
DISPLAY 0.638298 (-6230 3710);
PAINT MONO (-6230 3710);
DISPLAY INVISIBLE (-6230 3710);
WIRE 16 -1 (-5975 3475)(-5975 3425);
WIRE 16 -1 (-5975 3425)(-4225 3425);
FORCEPROP 2 LAST SIG_NAME VR_PVCCIN_CPU1_PH3_PHASE
J 0
(-5965 3435);
DISPLAY 0.617021 (-5965 3435);
PAINT ORANGE (-5965 3435);
FORCEPROP 2 LASTPROP $XRERR UNIQUE?
J 0
(-6205 3435);
DISPLAY 0.638298 (-6205 3435);
PAINT MONO (-6205 3435);
DISPLAY INVISIBLE (-6205 3435);
WIRE 16 -1 (-4225 3525)(-4225 3425);
WIRE 16 -1 (-3800 3525)(-4225 3525);
WIRE 16 -1 (-3800 3575)(-4225 3575);
WIRE 16 -1 (-4225 3575)(-4225 3700);
WIRE 16 -1 (-4225 3700)(-4875 3700);
FORCEPROP 2 LAST SIG_NAME VR_PVCCIN_CPU1_PH3_BOOT_R
J 0
(-4740 3710);
DISPLAY 0.617021 (-4740 3710);
PAINT ORANGE (-4740 3710);
FORCEPROP 2 LASTPROP $XRERR UNIQUE?
J 0
(-4980 3710);
DISPLAY 0.638298 (-4980 3710);
PAINT MONO (-4980 3710);
DISPLAY INVISIBLE (-4980 3710);
WIRE 16 -1 (-1025 4800)(-3975 4800);
FORCEPROP 2 LAST SIG_NAME VR_PVCCIN_CPU1_AIREF3
J 2
(-1437 4810);
DISPLAY 0.617021 (-1437 4810);
PAINT ORANGE (-1437 4810);
WIRE 16 -1 (-3975 3675)(-3975 4800);
WIRE 16 -1 (-3800 3675)(-3975 3675);
WIRE 16 -1 (-3975 3475)(-3975 3675);
WIRE 3 2175 (-5200 3750)(-4775 3750);
WIRE 3 2175 (-5200 3750)(-5200 3525);
WIRE 3 2175 (-4775 3750)(-4775 3525);
WIRE 3 2175 (-5200 3525)(-4775 3525);
WIRE 16 -1 (-2800 4425)(-950 4425);
FORCEPROP 2 LAST SIG_NAME ISENSE_PVCCIN_CPU1_PH3_IMON
J 0
(-2524 4444);
DISPLAY 0.617021 (-2524 4444);
PAINT ORANGE (-2524 4444);
WIRE 16 -1 (-2800 4225)(-700 4225);
FORCEPROP 0 LAST SIG_NAME VR_PVCCIN_CPU1_PH3_OCSET
J 0
(-2660 4235);
DISPLAY 0.617021 (-2660 4235);
PAINT ORANGE (-2660 4235);
FORCEPROP 2 LASTPROP $XRERR UNIQUE?
J 0
(-2900 4235);
DISPLAY 0.638298 (-2900 4235);
PAINT MONO (-2900 4235);
DISPLAY INVISIBLE (-2900 4235);
WIRE 16 -1 (-700 4225)(-700 4175);
WIRE 16 -1 (-5575 4425)(-3800 4425);
FORCEPROP 0 LAST VOLTAGE 5
J 0
(-4400 4500);
DISPLAY 1.021277 (-4400 4500);
PAINT SKYBLUE (-4400 4500);
DISPLAY INVISIBLE (-4400 4500);
FORCEPROP 2 LAST SIG_NAME VR_PVCCIN_CPU1_PH3_VCIN
J 0
(-4965 4435);
DISPLAY 0.617021 (-4965 4435);
PAINT ORANGE (-4965 4435);
FORCEPROP 2 LASTPROP $XRERR UNIQUE?
J 0
(-5205 4435);
DISPLAY 0.638298 (-5205 4435);
PAINT MONO (-5205 4435);
DISPLAY INVISIBLE (-5205 4435);
WIRE 16 -1 (-5575 4700)(-5575 4425);
WIRE 16 -1 (-5575 4250)(-5575 4425);
WIRE 16 -1 (-5575 4700)(-5375 4700);
WIRE 16 2175 (-5300 4350)(-4600 4350);
WIRE 16 2175 (-5300 4350)(-5300 3950);
WIRE 16 2175 (-4600 4350)(-4600 3950);
WIRE 16 2175 (-5300 3950)(-4600 3950);
WIRE 16 2175 (-5375 1725)(-4650 1725);
WIRE 16 2175 (-5375 1725)(-5375 1350);
WIRE 16 2175 (-4650 1725)(-4650 1350);
WIRE 16 2175 (-5375 1350)(-4650 1350);
WIRE 16 -1 (-4575 3875)(-3800 3875);
FORCEPROP 0 LAST SIG_NAME TP_PVCCIN_CPU1_PH3_GL_0
J 0
(-4560 3885);
DISPLAY 0.617021 (-4560 3885);
PAINT ORANGE (-4560 3885);
FORCEPROP 2 LASTPROP $XRERR UNIQUE?
J 0
(-4815 3875);
DISPLAY 0.638298 (-4815 3875);
PAINT MONO (-4815 3875);
DISPLAY INVISIBLE (-4815 3875);
WIRE 16 -1 (-3800 3925)(-4575 3925);
FORCEPROP 0 LAST SIG_NAME TP_PVCCIN_CPU1_PH3_GL_1
J 0
(-4560 3935);
DISPLAY 0.617021 (-4560 3935);
PAINT ORANGE (-4560 3935);
FORCEPROP 2 LASTPROP $XRERR UNIQUE?
J 0
(-4815 3925);
DISPLAY 0.638298 (-4815 3925);
PAINT MONO (-4815 3925);
DISPLAY INVISIBLE (-4815 3925);
WIRE 16 -1 (-2750 1575)(-2025 1575);
FORCEPROP 2 LAST SIG_NAME NC_PVCCIN_CPU1_PH4_P31
J 0
(-2610 1585);
DISPLAY 0.617021 (-2610 1585);
PAINT ORANGE (-2610 1585);
FORCEPROP 2 LASTPROP $XRERR UNIQUE?
J 0
(-1995 1575);
DISPLAY 0.638298 (-1995 1575);
PAINT MONO (-1995 1575);
DISPLAY INVISIBLE (-1995 1575);
DOT 1 (-350 550);
DOT 1 (-850 1025);
DOT 1 (-5000 2025);
DOT 1 (-400 3625);
DOT 1 (-825 3625);
DOT 1 (-1175 3625);
DOT 1 (-2575 725);
DOT 1 (-2575 775);
DOT 1 (-3850 1075);
DOT 1 (-3950 1625);
DOT 1 (-5700 1825);
DOT 1 (-5875 4375);
DOT 1 (-2000 1450);
DOT 1 (-3975 3675);
DOT 1 (-5075 2025);
DOT 1 (-7375 1250);
DOT 1 (-7375 1775);
DOT 1 (-7075 1250);
DOT 1 (-6725 1250);
DOT 1 (-7075 1775);
DOT 1 (-6725 1775);
DOT 1 (-6350 1775);
DOT 1 (-7375 3900);
DOT 1 (-7000 3900);
DOT 1 (-6625 3900);
DOT 1 (-6250 3900);
DOT 1 (-6025 1250);
DOT 1 (-5700 1250);
DOT 1 (-6025 1775);
DOT 1 (-5075 1250);
DOT 1 (-4900 2025);
DOT 1 (-5875 3900);
DOT 1 (-5575 3900);
DOT 1 (-5000 3900);
DOT 1 (-7375 4375);
DOT 1 (-7000 4375);
DOT 1 (-6625 4375);
DOT 1 (-6250 4375);
DOT 1 (-5575 4425);
DOT 1 (-5000 4700);
DOT 1 (-4925 4700);
DOT 1 (-4850 4700);
DOT 1 (-4375 4375);
DOT 1 (-4175 4225);
DOT 1 (-4075 1775);
DOT 1 (-3725 2375);
DOT 1 (-3725 2800);
DOT 1 (-3275 2375);
DOT 1 (-3275 2800);
DOT 1 (-2825 2375);
DOT 1 (-2825 2800);
DOT 1 (-2375 2375);
DOT 1 (-2600 3325);
DOT 1 (-2600 3375);
DOT 1 (-2600 3425);
DOT 1 (-1925 2375);
DOT 1 (-1000 2375);
DOT 1 (-2575 825);
DOT 1 (-2000 3625);
DOT 1 (-1925 2800);
DOT 1 (-1450 2375);
DOT 1 (-6350 1250);
DOT 1 (-2375 2800);
DOT 1 (-2050 4050);
DOT 1 (-400 3225);
DOT 1 (-1900 1025);
DOT 1 (-350 1025);
DOT 1 (-700 1025);
DOT 1 (-4150 2800);
DOT 1 (-1450 2800);
FORCENOTE
TP FAB1 CO-LAY WITH TI PARTS 11/16
(-5225 625) 0;
DISPLAY LEFT (-5225 625);
DISPLAY 0.851064 (-5225 625);
PAINT RED (-5225 625);
FORCENOTE
TP FAB1 3.01 OHM NEED CHANGE TO 2.2 OHM BUT WAIT FOR SYMBOL
(-1700 400) 0;
DISPLAY LEFT (-1700 400);
DISPLAY 0.851064 (-1700 400);
PAINT RED (-1700 400);
FORCENOTE
TP FAB1 CO-LAY WITH TI PARTS 11/16
(-1700 475) 0;
DISPLAY LEFT (-1700 475);
DISPLAY 0.851064 (-1700 475);
PAINT RED (-1700 475);
FORCENOTE
SPOF
(-6080 500) 0;
DISPLAY LEFT (-6080 500);
DISPLAY 1.808511 (-6080 500);
PAINT PURPLE (-6080 500);
FORCENOTE
PLACE ON TOP
(-5380 1250) 0;
DISPLAY LEFT (-5380 1250);
DISPLAY 1.553191 (-5380 1250);
PAINT PURPLE (-5380 1250);
FORCENOTE
PLACE ON TOP
(-5305 3875) 0;
DISPLAY LEFT (-5305 3875);
DISPLAY 1.553191 (-5305 3875);
PAINT PURPLE (-5305 3875);
FORCENOTE
ROOM=PVCCIN_CPU1_PWR_VR
(-7655 360) 0;
DISPLAY LEFT (-7655 360);
DISPLAY 2.446809 (-7655 360);
PAINT PURPLE (-7655 360);
FORCENOTE
SPOF
(-6180 3250) 0;
DISPLAY LEFT (-6180 3250);
DISPLAY 1.936170 (-6180 3250);
PAINT PURPLE (-6180 3250);
FORCENOTE
ROOM=PVCCIN_CPU1_PWR_VR
(-7555 3060) 0;
DISPLAY LEFT (-7555 3060);
DISPLAY 2.446809 (-7555 3060);
PAINT PURPLE (-7555 3060);
FORCENOTE
TP FAB1 CO-LAY WITH TI PARTS 11/16
(-5275 3275) 0;
DISPLAY LEFT (-5275 3275);
DISPLAY 0.851064 (-5275 3275);
PAINT RED (-5275 3275);
FORCENOTE
TP FAB1 CO-LAY WITH TI PARTS 11/16
(-1625 3050) 0;
DISPLAY LEFT (-1625 3050);
DISPLAY 0.851064 (-1625 3050);
PAINT RED (-1625 3050);
FORCENOTE
TP FAB1 3.01 OHM NEED CHANGE TO 2.2 OHM BUT WAIT FOR SYMBOL
(-1625 2975) 0;
DISPLAY LEFT (-1625 2975);
DISPLAY 0.851064 (-1625 2975);
PAINT RED (-1625 2975);
FORCENOTE
ROOM = PVCCIN_CPU1_DECAP_VR
(-3665 2840) 0;
DISPLAY LEFT (-3665 2840);
DISPLAY 2.446809 (-3665 2840);
PAINT PURPLE (-3665 2840);
FORCENOTE
TP FAB1 CO-LAY WITH TI PARTS 11/16
(-1675 3825) 0;
DISPLAY LEFT (-1675 3825);
DISPLAY 0.851064 (-1675 3825);
PAINT RED (-1675 3825);
FORCENOTE
TP FAB1 CO-LAY WITH TI PARTS 11/16
(-1725 1225) 0;
DISPLAY LEFT (-1725 1225);
DISPLAY 0.851064 (-1725 1225);
PAINT RED (-1725 1225);
QUIT
